FILE_TYPE = MACRO_DRAWING;
SET COLOR_WIRE YELLOW;
SET COLOR_PROP MONO;
SET COLOR_DOT WHITE;
SET COLOR_ARC YELLOW;
SET COLOR_BODY GREEN;
SET COLOR_NOTE MONO;
SET PROP_DISPLAY VALUE;
SET PAGE_NUMBER P206;
FORCEADD PVCCIO_CPU1..1
(-1375 4150);
FORCEPROP 3 LASTPIN (-1375 4100) SIG_NAME PVCCIO_CPU1\g
J 0
(-1365 4110);
DISPLAY 0.659574 (-1365 4110);
PAINT MONO (-1365 4110);
DISPLAY INVISIBLE (-1365 4110);
FORCEPROP 1 LAST PATH I1
J 0
(-1325 4175);
DISPLAY 0.872340 (-1325 4175);
PAINT AQUA (-1325 4175);
DISPLAY INVISIBLE (-1325 4175);
FORCEPROP 2 LAST CDS_LIB mstr_symbols
J 0
(-1375 4150);
PAINT ORANGE (-1375 4150);
DISPLAY INVISIBLE (-1375 4150);
FORCEPROP 1 LAST VOLTAGE 1.1V
J 0
(-1420 4107);
DISPLAY 0.340426 (-1420 4107);
PAINT SKYBLUE (-1420 4107);
DISPLAY INVISIBLE (-1420 4107);
FORCEPROP 1 LAST BODY_TYPE PLUMBING
J 0
(-1420 4107);
DISPLAY 0.340426 (-1420 4107);
PAINT GREEN (-1420 4107);
DISPLAY INVISIBLE (-1420 4107);
FORCEPROP 1 LAST HDL_POWER PVCCIO_CPU1
J 1
(-1375 4200);
DISPLAY 0.872340 (-1375 4200);
PAINT GREEN (-1375 4200);
DISPLAY INVISIBLE (-1375 4200);
FORCEADD OFFPAGE..2
(-1150 2825);
FORCEPROP 2 LAST $XR0 206 
J 0
(-961 2825);
DISPLAY 0.638298 (-961 2825);
PAINT MONO (-961 2825);
FORCEPROP 2 LAST ROOM PVCCIN_CPU1_VR
J 0
(-1575 2900);
DISPLAY 1.361702 (-1575 2900);
PAINT WHITE (-1575 2900);
DISPLAY INVISIBLE (-1575 2900);
FORCEPROP 2 LAST CDS_LIB mstr_standard
J 0
(-1150 2825);
PAINT ORANGE (-1150 2825);
DISPLAY INVISIBLE (-1150 2825);
FORCEPROP 2 LAST PATH I10
J 0
(-950 2875);
DISPLAY 1.021277 (-950 2875);
PAINT ORANGE (-950 2875);
DISPLAY INVISIBLE (-950 2875);
FORCEPROP 1 LAST OFFPAGE TRUE
J 0
(-825 2700);
DISPLAY 1.170213 (-825 2700);
PAINT GREEN (-825 2700);
DISPLAY INVISIBLE (-825 2700);
FORCEPROP 1 LAST COMMENT_BODY TRUE
J 0
(-1195 2730);
DISPLAY 1.170213 (-1195 2730);
PAINT PEACH (-1195 2730);
DISPLAY INVISIBLE (-1195 2730);
FORCEADD OFFPAGE..1
(-7500 1675);
FORCEPROP 2 LAST $XR0 209 
J 0
(-7752 1675);
DISPLAY 0.638298 (-7752 1675);
PAINT MONO (-7752 1675);
FORCEPROP 2 LAST ROOM PVCCIN_CPU1_VR
J 0
(-8050 1750);
DISPLAY 1.361702 (-8050 1750);
PAINT WHITE (-8050 1750);
DISPLAY INVISIBLE (-8050 1750);
FORCEPROP 2 LAST CDS_LIB mstr_standard
J 0
(-7500 1675);
PAINT ORANGE (-7500 1675);
DISPLAY INVISIBLE (-7500 1675);
FORCEPROP 2 LAST PATH I100
J 0
(-7450 1750);
DISPLAY 1.021277 (-7450 1750);
PAINT ORANGE (-7450 1750);
DISPLAY INVISIBLE (-7450 1750);
FORCEPROP 1 LAST OFFPAGE TRUE
J 0
(-7175 1550);
DISPLAY 1.170213 (-7175 1550);
PAINT GREEN (-7175 1550);
DISPLAY INVISIBLE (-7175 1550);
FORCEPROP 1 LAST COMMENT_BODY TRUE
J 0
(-7375 1575);
DISPLAY 1.170213 (-7375 1575);
PAINT PEACH (-7375 1575);
DISPLAY INVISIBLE (-7375 1575);
FORCEADD OFFPAGE..1
(-7500 1525);
FORCEPROP 2 LAST $XR0 210 
J 0
(-7752 1525);
DISPLAY 0.638298 (-7752 1525);
PAINT MONO (-7752 1525);
FORCEPROP 2 LAST ROOM PVCCIN_CPU1_VR
J 0
(-8050 1600);
DISPLAY 1.361702 (-8050 1600);
PAINT WHITE (-8050 1600);
DISPLAY INVISIBLE (-8050 1600);
FORCEPROP 2 LAST CDS_LIB mstr_standard
J 0
(-7500 1525);
PAINT ORANGE (-7500 1525);
DISPLAY INVISIBLE (-7500 1525);
FORCEPROP 2 LAST PATH I101
J 0
(-7450 1600);
DISPLAY 1.021277 (-7450 1600);
PAINT ORANGE (-7450 1600);
DISPLAY INVISIBLE (-7450 1600);
FORCEPROP 1 LAST OFFPAGE TRUE
J 0
(-7175 1400);
DISPLAY 1.170213 (-7175 1400);
PAINT GREEN (-7175 1400);
DISPLAY INVISIBLE (-7175 1400);
FORCEPROP 1 LAST COMMENT_BODY TRUE
J 0
(-7375 1425);
DISPLAY 1.170213 (-7375 1425);
PAINT PEACH (-7375 1425);
DISPLAY INVISIBLE (-7375 1425);
FORCEADD OFFPAGE..1
(-7500 1475);
FORCEPROP 2 LAST $XR0 210 
J 0
(-7752 1475);
DISPLAY 0.638298 (-7752 1475);
PAINT MONO (-7752 1475);
FORCEPROP 2 LAST ROOM PVCCIN_CPU1_VR
J 0
(-8050 1550);
DISPLAY 1.361702 (-8050 1550);
PAINT WHITE (-8050 1550);
DISPLAY INVISIBLE (-8050 1550);
FORCEPROP 2 LAST CDS_LIB mstr_standard
J 0
(-7500 1475);
PAINT ORANGE (-7500 1475);
DISPLAY INVISIBLE (-7500 1475);
FORCEPROP 2 LAST PATH I102
J 0
(-7450 1550);
DISPLAY 1.021277 (-7450 1550);
PAINT ORANGE (-7450 1550);
DISPLAY INVISIBLE (-7450 1550);
FORCEPROP 1 LAST OFFPAGE TRUE
J 0
(-7175 1350);
DISPLAY 1.170213 (-7175 1350);
PAINT GREEN (-7175 1350);
DISPLAY INVISIBLE (-7175 1350);
FORCEPROP 1 LAST COMMENT_BODY TRUE
J 0
(-7375 1375);
DISPLAY 1.170213 (-7375 1375);
PAINT PEACH (-7375 1375);
DISPLAY INVISIBLE (-7375 1375);
FORCEADD P3V3_STBY..1
(-4350 4600);
FORCEPROP 3 LASTPIN (-4350 4550) SIG_NAME P3V3_STBY\g
J 0
(-4340 4560);
DISPLAY 0.659574 (-4340 4560);
PAINT MONO (-4340 4560);
DISPLAY INVISIBLE (-4340 4560);
FORCEPROP 1 LAST VOLTAGE 3.3V
J 0
(-4395 4557);
DISPLAY 0.340426 (-4395 4557);
PAINT SKYBLUE (-4395 4557);
DISPLAY INVISIBLE (-4395 4557);
FORCEPROP 1 LAST PATH I103
J 0
(-4305 4602);
DISPLAY 0.340426 (-4305 4602);
PAINT GREEN (-4305 4602);
DISPLAY INVISIBLE (-4305 4602);
FORCEPROP 2 LAST CDS_LIB mstr_symbols
J 0
(-4350 4600);
PAINT ORANGE (-4350 4600);
DISPLAY INVISIBLE (-4350 4600);
FORCEPROP 1 LAST SIZE 1B
J 0
(-4305 4622);
DISPLAY 0.340426 (-4305 4622);
PAINT GREEN (-4305 4622);
DISPLAY INVISIBLE (-4305 4622);
FORCEPROP 1 LAST BODY_TYPE PLUMBING
J 0
(-4395 4557);
DISPLAY 0.340426 (-4395 4557);
PAINT GREEN (-4395 4557);
DISPLAY INVISIBLE (-4395 4557);
FORCEPROP 1 LAST HDL_POWER P3V3_STBY
J 0
(-4650 4475);
DISPLAY 0.872340 (-4650 4475);
PAINT GREEN (-4650 4475);
DISPLAY INVISIBLE (-4650 4475);
FORCEADD P3V3_STBY..1
(-3075 4575);
FORCEPROP 3 LASTPIN (-3075 4525) SIG_NAME P3V3_STBY\g
J 0
(-3065 4535);
DISPLAY 0.659574 (-3065 4535);
PAINT MONO (-3065 4535);
DISPLAY INVISIBLE (-3065 4535);
FORCEPROP 1 LAST VOLTAGE 3.3V
J 0
(-3120 4532);
DISPLAY 0.340426 (-3120 4532);
PAINT SKYBLUE (-3120 4532);
DISPLAY INVISIBLE (-3120 4532);
FORCEPROP 2 LAST CDS_LIB mstr_symbols
J 0
(-3075 4575);
PAINT ORANGE (-3075 4575);
DISPLAY INVISIBLE (-3075 4575);
FORCEPROP 1 LAST PATH I104
J 0
(-3030 4577);
DISPLAY 0.340426 (-3030 4577);
PAINT GREEN (-3030 4577);
DISPLAY INVISIBLE (-3030 4577);
FORCEPROP 1 LAST SIZE 1B
J 0
(-3030 4597);
DISPLAY 0.340426 (-3030 4597);
PAINT GREEN (-3030 4597);
DISPLAY INVISIBLE (-3030 4597);
FORCEPROP 1 LAST BODY_TYPE PLUMBING
J 0
(-3120 4532);
DISPLAY 0.340426 (-3120 4532);
PAINT GREEN (-3120 4532);
DISPLAY INVISIBLE (-3120 4532);
FORCEPROP 1 LAST HDL_POWER P3V3_STBY
J 0
(-3375 4450);
DISPLAY 0.872340 (-3375 4450);
PAINT GREEN (-3375 4450);
DISPLAY INVISIBLE (-3375 4450);
FORCEADD OFFPAGE..2
(-1150 3125);
FORCEPROP 2 LAST $XR0 95 
J 0
(-961 3125);
DISPLAY 0.638298 (-961 3125);
PAINT MONO (-961 3125);
FORCEPROP 2 LAST ROOM PVCCIN_CPU1_VR
J 0
(-1575 3200);
DISPLAY 1.361702 (-1575 3200);
PAINT WHITE (-1575 3200);
DISPLAY INVISIBLE (-1575 3200);
FORCEPROP 2 LAST CDS_LIB mstr_standard
J 0
(-1150 3125);
PAINT ORANGE (-1150 3125);
DISPLAY INVISIBLE (-1150 3125);
FORCEPROP 2 LAST PATH I109
J 0
(-975 3200);
DISPLAY 1.021277 (-975 3200);
PAINT ORANGE (-975 3200);
DISPLAY INVISIBLE (-975 3200);
FORCEPROP 1 LAST OFFPAGE TRUE
J 0
(-825 3000);
DISPLAY 1.170213 (-825 3000);
PAINT GREEN (-825 3000);
DISPLAY INVISIBLE (-825 3000);
FORCEPROP 1 LAST COMMENT_BODY TRUE
J 0
(-1195 3030);
DISPLAY 1.170213 (-1195 3030);
PAINT PEACH (-1195 3030);
DISPLAY INVISIBLE (-1195 3030);
FORCEADD OFFPAGE..3
(-1175 2775);
FORCEPROP 2 LAST $XR0 55 
J 0
(-961 2775);
DISPLAY 0.638298 (-961 2775);
PAINT MONO (-961 2775);
FORCEPROP 2 LAST $XR1 193 
J 0
(-871 2775);
DISPLAY 0.638298 (-871 2775);
PAINT MONO (-871 2775);
FORCEPROP 2 LAST $XR2 213 
J 0
(-751 2775);
DISPLAY 0.638298 (-751 2775);
PAINT MONO (-751 2775);
FORCEPROP 2 LAST ROOM PVCCIN_CPU1_VR
J 0
(-1575 2850);
DISPLAY 1.361702 (-1575 2850);
PAINT WHITE (-1575 2850);
DISPLAY INVISIBLE (-1575 2850);
FORCEPROP 2 LAST CDS_LIB mstr_standard
J 0
(-1175 2775);
PAINT ORANGE (-1175 2775);
DISPLAY INVISIBLE (-1175 2775);
FORCEPROP 2 LAST PATH I11
J 0
(-975 2850);
DISPLAY 1.021277 (-975 2850);
PAINT ORANGE (-975 2850);
DISPLAY INVISIBLE (-975 2850);
FORCEPROP 1 LAST OFFPAGE TRUE
J 0
(-850 2650);
DISPLAY 1.170213 (-850 2650);
PAINT GREEN (-850 2650);
DISPLAY INVISIBLE (-850 2650);
FORCEPROP 1 LAST COMMENT_BODY TRUE
J 0
(-1225 2675);
DISPLAY 1.170213 (-1225 2675);
PAINT PEACH (-1225 2675);
DISPLAY INVISIBLE (-1225 2675);
FORCEADD RES..2
(-4500 925);
FORCEPROP 1 LASTPIN (-4500 1025) $PN 1
J 0
(-4495 987);
DISPLAY 0.617021 (-4495 987);
PAINT WHITE (-4495 987);
FORCEPROP 1 LASTPIN (-4500 825) $PN 2
J 0
(-4495 835);
DISPLAY 0.617021 (-4495 835);
PAINT WHITE (-4495 835);
FORCEPROP 1 LAST TOLERANCE 1%
J 0
(-4455 950);
DISPLAY 0.617021 (-4455 950);
PAINT SKYBLUE (-4455 950);
FORCEPROP 1 LAST WATTAGE 1/16W
J 0
(-4460 900);
DISPLAY 0.617021 (-4460 900);
PAINT SKYBLUE (-4460 900);
FORCEPROP 1 LAST MATERIAL CHIP
J 0
(-4460 850);
DISPLAY 0.617021 (-4460 850);
PAINT SKYBLUE (-4460 850);
FORCEPROP 1 LAST PACK_TYPE 0402
J 0
(-4460 750);
DISPLAY 0.617021 (-4460 750);
PAINT SKYBLUE (-4460 750);
FORCEPROP 1 LAST PART_NUMBER G21796-043
J 0
(-4460 800);
DISPLAY 0.617021 (-4460 800);
PAINT BLUE (-4460 800);
FORCEPROP 1 LAST VALUE 3.16K
J 0
(-4455 1000);
DISPLAY 0.617021 (-4455 1000);
PAINT SKYBLUE (-4455 1000);
FORCEPROP 1 LAST LOCATION R9N7
J 0
(-4455 1050);
DISPLAY 0.617021 (-4455 1050);
PAINT AQUA (-4455 1050);
FORCEPROP 2 LAST CDS_LIB mstr_discrete
J 0
(-4500 925);
PAINT ORANGE (-4500 925);
DISPLAY INVISIBLE (-4500 925);
FORCEPROP 0 LAST ROOM PVCCIN_CPU1_VR
J 0
(-4450 1150);
DISPLAY 1.021277 (-4450 1150);
PAINT ORANGE (-4450 1150);
DISPLAY INVISIBLE (-4450 1150);
FORCEPROP 1 LAST PATH I111
J 0
(-4450 1100);
DISPLAY 0.978723 (-4450 1100);
PAINT WHITE (-4450 1100);
DISPLAY INVISIBLE (-4450 1100);
FORCEPROP 2 LAST CDS_LOCATION R9N7
J 0
(-4455 1050);
DISPLAY 0.617021 (-4455 1050);
PAINT AQUA (-4455 1050);
DISPLAY INVISIBLE (-4455 1050);
FORCEPROP 0 LAST SEC 1
J 0
(-4450 1200);
DISPLAY 0.680851 (-4450 1200);
PAINT MONO (-4450 1200);
DISPLAY INVISIBLE (-4450 1200);
FORCEPROP 2 LAST SEC_TYPE 0402
J 0
(-4450 1150);
DISPLAY 1.021277 (-4450 1150);
PAINT ORANGE (-4450 1150);
DISPLAY INVISIBLE (-4450 1150);
FORCEADD RES..2
(-4825 925);
FORCEPROP 1 LAST PACK_TYPE 0402
J 0
(-4785 750);
DISPLAY 0.617021 (-4785 750);
PAINT SKYBLUE (-4785 750);
FORCEPROP 1 LASTPIN (-4825 825) $PN 2
J 0
(-4820 835);
DISPLAY 0.617021 (-4820 835);
PAINT WHITE (-4820 835);
FORCEPROP 1 LASTPIN (-4825 1025) $PN 1
J 0
(-4820 987);
DISPLAY 0.617021 (-4820 987);
PAINT WHITE (-4820 987);
FORCEPROP 1 LAST TOLERANCE 1%
J 0
(-4780 950);
DISPLAY 0.617021 (-4780 950);
PAINT SKYBLUE (-4780 950);
FORCEPROP 1 LAST MATERIAL CHIP
J 0
(-4785 850);
DISPLAY 0.617021 (-4785 850);
PAINT SKYBLUE (-4785 850);
FORCEPROP 1 LAST WATTAGE 1/16W
J 0
(-4785 900);
DISPLAY 0.617021 (-4785 900);
PAINT SKYBLUE (-4785 900);
FORCEPROP 1 LAST PART_NUMBER G21796-082
J 0
(-4785 800);
DISPLAY 0.617021 (-4785 800);
PAINT BLUE (-4785 800);
FORCEPROP 1 LAST VALUE 4.02K
J 0
(-4780 1000);
DISPLAY 0.617021 (-4780 1000);
PAINT SKYBLUE (-4780 1000);
FORCEPROP 1 LAST LOCATION R9N8
J 0
(-4780 1050);
DISPLAY 0.617021 (-4780 1050);
PAINT AQUA (-4780 1050);
FORCEPROP 2 LAST CDS_LIB mstr_discrete
J 0
(-4825 925);
PAINT ORANGE (-4825 925);
DISPLAY INVISIBLE (-4825 925);
FORCEPROP 0 LAST ROOM PVCCIN_CPU1_VR
J 0
(-4775 1150);
DISPLAY 1.021277 (-4775 1150);
PAINT ORANGE (-4775 1150);
DISPLAY INVISIBLE (-4775 1150);
FORCEPROP 1 LAST PATH I112
J 0
(-4775 1100);
DISPLAY 0.978723 (-4775 1100);
PAINT WHITE (-4775 1100);
DISPLAY INVISIBLE (-4775 1100);
FORCEPROP 2 LAST CDS_LOCATION R9N8
J 0
(-4780 1050);
DISPLAY 0.617021 (-4780 1050);
PAINT AQUA (-4780 1050);
DISPLAY INVISIBLE (-4780 1050);
FORCEPROP 0 LAST SEC 1
J 0
(-4775 1200);
DISPLAY 0.680851 (-4775 1200);
PAINT MONO (-4775 1200);
DISPLAY INVISIBLE (-4775 1200);
FORCEPROP 2 LAST SEC_TYPE 0402
J 0
(-4775 1150);
DISPLAY 1.021277 (-4775 1150);
PAINT ORANGE (-4775 1150);
DISPLAY INVISIBLE (-4775 1150);
FORCEADD RES..1
(-1200 3375);
FORCEPROP 1 LASTPIN (-1300 3375) $PN 1
J 0
(-1288 3387);
DISPLAY 0.617021 (-1288 3387);
PAINT ORANGE (-1288 3387);
FORCEPROP 1 LAST WATTAGE 1/16W
J 2
(-1225 3225);
DISPLAY 0.617021 (-1225 3225);
PAINT SKYBLUE (-1225 3225);
FORCEPROP 1 LAST VALUE 22.1
J 2
(-1225 3275);
DISPLAY 0.617021 (-1225 3275);
PAINT SKYBLUE (-1225 3275);
FORCEPROP 1 LAST MATERIAL CHIP
J 0
(-1200 3225);
DISPLAY 0.617021 (-1200 3225);
PAINT SKYBLUE (-1200 3225);
FORCEPROP 1 LAST TOLERANCE 1.0%
J 0
(-1200 3275);
DISPLAY 0.617021 (-1200 3275);
PAINT SKYBLUE (-1200 3275);
FORCEPROP 1 LAST LOCATION R1C30
J 0
(-1250 3425);
DISPLAY 0.617021 (-1250 3425);
PAINT AQUA (-1250 3425);
FORCEPROP 1 LASTPIN (-1100 3375) $PN 2
J 0
(-1138 3387);
DISPLAY 0.617021 (-1138 3387);
PAINT ORANGE (-1138 3387);
FORCEPROP 1 LAST PART_NUMBER G21796-250
J 0
(-1250 3475);
DISPLAY 0.617021 (-1250 3475);
PAINT BLUE (-1250 3475);
FORCEPROP 1 LAST PACK_TYPE 0402
J 0
(-950 3225);
DISPLAY 0.617021 (-950 3225);
PAINT SKYBLUE (-950 3225);
FORCEPROP 2 LAST CDS_LIB mstr_discrete
J 0
(-1200 3375);
PAINT MONO (-1200 3375);
DISPLAY INVISIBLE (-1200 3375);
FORCEPROP 2 LAST CDS_LOCATION R1C30
J 0
(-1250 3425);
DISPLAY 0.617021 (-1250 3425);
PAINT AQUA (-1250 3425);
DISPLAY INVISIBLE (-1250 3425);
FORCEPROP 1 LAST PATH I113
J 0
(-1250 3525);
DISPLAY 0.978723 (-1250 3525);
PAINT WHITE (-1250 3525);
DISPLAY INVISIBLE (-1250 3525);
FORCEPROP 2 LAST ROOM PVCCIN_CPU1_VR
J 0
(-1250 3475);
DISPLAY 1.361702 (-1250 3475);
PAINT WHITE (-1250 3475);
DISPLAY INVISIBLE (-1250 3475);
FORCEPROP 2 LAST SEC 1
J 0
(-1250 3575);
DISPLAY 0.680851 (-1250 3575);
PAINT MONO (-1250 3575);
DISPLAY INVISIBLE (-1250 3575);
FORCEPROP 2 LAST SEC_TYPE 0402
J 0
(-1250 3575);
DISPLAY 1.021277 (-1250 3575);
PAINT ORANGE (-1250 3575);
DISPLAY INVISIBLE (-1250 3575);
FORCEADD CAP..1
(-1450 2150);
FORCEPROP 1 LAST PART_NUMBER A36096-046
J 0
(-1400 2000);
DISPLAY 0.617021 (-1400 2000);
PAINT BLUE (-1400 2000);
FORCEPROP 1 LAST PACK_TYPE 0402LF
J 0
(-1400 1950);
DISPLAY 0.617021 (-1400 1950);
PAINT SKYBLUE (-1400 1950);
FORCEPROP 1 LASTPIN (-1450 2050) $PN 2
J 0
(-1440 2030);
DISPLAY 0.617021 (-1440 2030);
PAINT ORANGE (-1440 2030);
FORCEPROP 1 LASTPIN (-1450 2250) $PN 1
J 0
(-1440 2230);
DISPLAY 0.617021 (-1440 2230);
PAINT ORANGE (-1440 2230);
FORCEPROP 1 LAST TOLERANCE 10%
J 0
(-1400 2100);
DISPLAY 0.617021 (-1400 2100);
PAINT SKYBLUE (-1400 2100);
FORCEPROP 1 LAST VOLTAGE 50V
J 0
(-1400 2150);
DISPLAY 0.617021 (-1400 2150);
PAINT SKYBLUE (-1400 2150);
FORCEPROP 1 LAST MATERIAL X7R
J 0
(-1400 2050);
DISPLAY 0.617021 (-1400 2050);
PAINT SKYBLUE (-1400 2050);
FORCEPROP 1 LAST VALUE 1000PF
J 0
(-1400 2200);
DISPLAY 0.617021 (-1400 2200);
PAINT SKYBLUE (-1400 2200);
FORCEPROP 1 LAST LOCATION C1C23
J 0
(-1400 2250);
DISPLAY 0.617021 (-1400 2250);
PAINT AQUA (-1400 2250);
FORCEPROP 2 LAST CDS_LIB mstr_discrete
J 0
(-1450 2150);
PAINT MONO (-1450 2150);
DISPLAY INVISIBLE (-1450 2150);
FORCEPROP 2 LAST CDS_LOCATION C1C23
J 0
(-1400 2250);
DISPLAY 0.617021 (-1400 2250);
PAINT AQUA (-1400 2250);
DISPLAY INVISIBLE (-1400 2250);
FORCEPROP 1 LAST PATH I114
J 0
(-1400 2300);
DISPLAY 0.978723 (-1400 2300);
PAINT WHITE (-1400 2300);
DISPLAY INVISIBLE (-1400 2300);
FORCEPROP 2 LAST SEC_TYPE 0402LF
J 0
(-1400 2350);
DISPLAY 1.021277 (-1400 2350);
PAINT ORANGE (-1400 2350);
DISPLAY INVISIBLE (-1400 2350);
FORCEPROP 2 LAST SEC 1
J 0
(-1400 2350);
DISPLAY 0.680851 (-1400 2350);
PAINT MONO (-1400 2350);
DISPLAY INVISIBLE (-1400 2350);
FORCEPROP 0 LAST ROOM PVCCIN_CPU1_VR
J 0
(-1400 2350);
DISPLAY 1.021277 (-1400 2350);
PAINT ORANGE (-1400 2350);
DISPLAY INVISIBLE (-1400 2350);
FORCEADD GND..1
(-1450 1925);
FORCEPROP 3 LASTPIN (-1450 1975) SIG_NAME GND\g
J 0
(-1440 1985);
DISPLAY 0.659574 (-1440 1985);
PAINT MONO (-1440 1985);
DISPLAY INVISIBLE (-1440 1985);
FORCEPROP 1 LAST VOLTAGE 0
J 0
(-1450 1925);
PAINT SKYBLUE (-1450 1925);
DISPLAY INVISIBLE (-1450 1925);
FORCEPROP 1 LAST SIZE 1B
J 0
(-1375 1875);
DISPLAY 1.170213 (-1375 1875);
PAINT AQUA (-1375 1875);
DISPLAY INVISIBLE (-1375 1875);
FORCEPROP 2 LAST CDS_LIB mstr_symbols
J 0
(-1450 1925);
PAINT MONO (-1450 1925);
DISPLAY INVISIBLE (-1450 1925);
FORCEPROP 1 LAST PATH I115
J 0
(-1375 1925);
DISPLAY 0.872340 (-1375 1925);
PAINT AQUA (-1375 1925);
DISPLAY INVISIBLE (-1375 1925);
FORCEPROP 2 LAST ROOM PVCCIN_CPU1_VR
J 0
(-2025 2000);
DISPLAY 1.361702 (-2025 2000);
PAINT WHITE (-2025 2000);
DISPLAY INVISIBLE (-2025 2000);
FORCEPROP 1 LAST BODY_TYPE PLUMBING
J 0
(-1495 1882);
DISPLAY 0.340426 (-1495 1882);
PAINT GREEN (-1495 1882);
DISPLAY INVISIBLE (-1495 1882);
FORCEPROP 1 LAST HDL_POWER GND
J 0
(-1450 2075);
DISPLAY 1.170213 (-1450 2075);
PAINT GREEN (-1450 2075);
DISPLAY INVISIBLE (-1450 2075);
FORCEADD RES..1
(-2175 2725);
FORCEPROP 1 LAST WATTAGE 1/16W
J 2
(-2200 2575);
DISPLAY 0.617021 (-2200 2575);
PAINT SKYBLUE (-2200 2575);
FORCEPROP 1 LAST VALUE 33.2
J 2
(-2200 2625);
DISPLAY 0.617021 (-2200 2625);
PAINT SKYBLUE (-2200 2625);
FORCEPROP 1 LASTPIN (-2275 2725) $PN 1
J 0
(-2263 2737);
DISPLAY 0.617021 (-2263 2737);
PAINT ORANGE (-2263 2737);
FORCEPROP 1 LAST LOCATION R1D1
J 0
(-2225 2775);
DISPLAY 0.617021 (-2225 2775);
PAINT AQUA (-2225 2775);
FORCEPROP 1 LAST TOLERANCE 1%
J 0
(-2175 2625);
DISPLAY 0.617021 (-2175 2625);
PAINT SKYBLUE (-2175 2625);
FORCEPROP 1 LAST MATERIAL CHIP
J 0
(-2175 2575);
DISPLAY 0.617021 (-2175 2575);
PAINT SKYBLUE (-2175 2575);
FORCEPROP 1 LASTPIN (-2075 2725) $PN 2
J 0
(-2113 2737);
DISPLAY 0.617021 (-2113 2737);
PAINT ORANGE (-2113 2737);
FORCEPROP 1 LAST PART_NUMBER G21796-074
J 0
(-2225 2825);
DISPLAY 0.617021 (-2225 2825);
PAINT BLUE (-2225 2825);
FORCEPROP 1 LAST PACK_TYPE 0402
J 0
(-1925 2575);
DISPLAY 0.617021 (-1925 2575);
PAINT SKYBLUE (-1925 2575);
FORCEPROP 2 LAST CDS_LOCATION R1D1
J 0
(-2225 2775);
DISPLAY 0.617021 (-2225 2775);
PAINT AQUA (-2225 2775);
DISPLAY INVISIBLE (-2225 2775);
FORCEPROP 2 LAST CDS_LIB mstr_discrete
J 0
(-2175 2725);
PAINT MONO (-2175 2725);
DISPLAY INVISIBLE (-2175 2725);
FORCEPROP 1 LAST PATH I116
J 0
(-2225 2875);
DISPLAY 0.978723 (-2225 2875);
PAINT WHITE (-2225 2875);
DISPLAY INVISIBLE (-2225 2875);
FORCEPROP 2 LAST SEC 1
J 0
(-2225 2925);
DISPLAY 0.680851 (-2225 2925);
PAINT MONO (-2225 2925);
DISPLAY INVISIBLE (-2225 2925);
FORCEPROP 2 LAST SEC_TYPE 0402
J 0
(-2225 2925);
DISPLAY 1.021277 (-2225 2925);
PAINT ORANGE (-2225 2925);
DISPLAY INVISIBLE (-2225 2925);
FORCEADD RES..1
(-2425 3025);
FORCEPROP 1 LAST WATTAGE 1/16W
J 2
(-2450 2875);
DISPLAY 0.617021 (-2450 2875);
PAINT SKYBLUE (-2450 2875);
FORCEPROP 1 LAST VALUE 33.2
J 2
(-2450 2925);
DISPLAY 0.617021 (-2450 2925);
PAINT SKYBLUE (-2450 2925);
FORCEPROP 1 LASTPIN (-2525 3025) $PN 1
J 0
(-2513 3037);
DISPLAY 0.617021 (-2513 3037);
PAINT ORANGE (-2513 3037);
FORCEPROP 1 LASTPIN (-2325 3025) $PN 2
J 0
(-2363 3037);
DISPLAY 0.617021 (-2363 3037);
PAINT ORANGE (-2363 3037);
FORCEPROP 1 LAST MATERIAL CHIP
J 0
(-2425 2875);
DISPLAY 0.617021 (-2425 2875);
PAINT SKYBLUE (-2425 2875);
FORCEPROP 1 LAST TOLERANCE 1%
J 0
(-2425 2925);
DISPLAY 0.617021 (-2425 2925);
PAINT SKYBLUE (-2425 2925);
FORCEPROP 1 LAST PACK_TYPE 0402
J 0
(-2175 2875);
DISPLAY 0.617021 (-2175 2875);
PAINT SKYBLUE (-2175 2875);
FORCEPROP 1 LAST LOCATION R9P3
J 0
(-2475 3075);
DISPLAY 0.617021 (-2475 3075);
PAINT AQUA (-2475 3075);
FORCEPROP 1 LAST PART_NUMBER G21796-074
J 0
(-2475 3125);
DISPLAY 0.617021 (-2475 3125);
PAINT BLUE (-2475 3125);
FORCEPROP 2 LAST CDS_LIB mstr_discrete
J 0
(-2425 3025);
PAINT MONO (-2425 3025);
DISPLAY INVISIBLE (-2425 3025);
FORCEPROP 2 LAST SEC_TYPE 0402
J 0
(-2475 3225);
DISPLAY 1.021277 (-2475 3225);
PAINT ORANGE (-2475 3225);
DISPLAY INVISIBLE (-2475 3225);
FORCEPROP 2 LAST SEC 1
J 0
(-2475 3225);
DISPLAY 0.680851 (-2475 3225);
PAINT MONO (-2475 3225);
DISPLAY INVISIBLE (-2475 3225);
FORCEPROP 2 LAST CDS_LOCATION R9P3
J 0
(-2475 3075);
DISPLAY 0.617021 (-2475 3075);
PAINT AQUA (-2475 3075);
DISPLAY INVISIBLE (-2475 3075);
FORCEPROP 1 LAST PATH I117
J 0
(-2475 3175);
DISPLAY 0.978723 (-2475 3175);
PAINT WHITE (-2475 3175);
DISPLAY INVISIBLE (-2475 3175);
FORCEADD RES..1
(-5200 2275);
FORCEPROP 1 LAST VALUE 0.0
J 2
(-5300 2175);
DISPLAY 0.617021 (-5300 2175);
PAINT SKYBLUE (-5300 2175);
FORCEPROP 1 LAST TOLERANCE 5%
J 0
(-5250 2175);
DISPLAY 0.617021 (-5250 2175);
PAINT SKYBLUE (-5250 2175);
FORCEPROP 1 LAST WATTAGE 1/16W
J 2
(-5225 2125);
DISPLAY 0.617021 (-5225 2125);
PAINT SKYBLUE (-5225 2125);
FORCEPROP 1 LASTPIN (-5300 2275) $PN 1
J 0
(-5288 2287);
DISPLAY 0.617021 (-5288 2287);
PAINT ORANGE (-5288 2287);
FORCEPROP 1 LASTPIN (-5100 2275) $PN 2
J 0
(-5138 2287);
DISPLAY 0.617021 (-5138 2287);
PAINT ORANGE (-5138 2287);
FORCEPROP 1 LAST MATERIAL CHIP
J 0
(-5200 2125);
DISPLAY 0.617021 (-5200 2125);
PAINT SKYBLUE (-5200 2125);
FORCEPROP 1 LAST PACK_TYPE 0402
J 0
(-5125 2175);
DISPLAY 0.617021 (-5125 2175);
PAINT SKYBLUE (-5125 2175);
FORCEPROP 1 LAST PART_NUMBER G21497-005
J 0
(-5350 2225);
DISPLAY 0.617021 (-5350 2225);
PAINT BLUE (-5350 2225);
FORCEPROP 1 LAST LOCATION R9N16
J 0
(-5250 2325);
DISPLAY 0.617021 (-5250 2325);
PAINT AQUA (-5250 2325);
FORCEPROP 2 LAST CDS_LIB mstr_discrete
J 0
(-5200 2275);
PAINT ORANGE (-5200 2275);
DISPLAY INVISIBLE (-5200 2275);
FORCEPROP 2 LAST SEC_TYPE 0402
J 0
(-5250 2475);
DISPLAY 1.021277 (-5250 2475);
PAINT ORANGE (-5250 2475);
DISPLAY INVISIBLE (-5250 2475);
FORCEPROP 2 LAST SEC 1
J 0
(-5250 2475);
PAINT MONO (-5250 2475);
DISPLAY INVISIBLE (-5250 2475);
FORCEPROP 2 LAST CDS_LOCATION R9N16
J 0
(-5250 2325);
DISPLAY 0.617021 (-5250 2325);
PAINT AQUA (-5250 2325);
DISPLAY INVISIBLE (-5250 2325);
FORCEPROP 1 LAST PATH I119
J 0
(-5250 2425);
DISPLAY 0.978723 (-5250 2425);
PAINT WHITE (-5250 2425);
DISPLAY INVISIBLE (-5250 2425);
FORCEPROP 2 LAST ROOM PVCCIN_CPU0_VR
J 0
(-5250 2375);
DISPLAY 1.361702 (-5250 2375);
PAINT ORANGE (-5250 2375);
DISPLAY INVISIBLE (-5250 2375);
FORCEADD OFFPAGE..2
(-1150 2725);
FORCEPROP 2 LAST $XR0 190 
J 0
(-961 2725);
DISPLAY 0.638298 (-961 2725);
PAINT MONO (-961 2725);
FORCEPROP 2 LAST ROOM PVCCIN_CPU1_VR
J 0
(-1575 2800);
DISPLAY 1.361702 (-1575 2800);
PAINT WHITE (-1575 2800);
DISPLAY INVISIBLE (-1575 2800);
FORCEPROP 2 LAST CDS_LIB mstr_standard
J 0
(-1150 2725);
PAINT ORANGE (-1150 2725);
DISPLAY INVISIBLE (-1150 2725);
FORCEPROP 2 LAST PATH I12
J 0
(-975 2800);
DISPLAY 1.021277 (-975 2800);
PAINT ORANGE (-975 2800);
DISPLAY INVISIBLE (-975 2800);
FORCEPROP 1 LAST OFFPAGE TRUE
J 0
(-825 2600);
DISPLAY 1.170213 (-825 2600);
PAINT GREEN (-825 2600);
DISPLAY INVISIBLE (-825 2600);
FORCEPROP 1 LAST COMMENT_BODY TRUE
J 0
(-1195 2630);
DISPLAY 1.170213 (-1195 2630);
PAINT PEACH (-1195 2630);
DISPLAY INVISIBLE (-1195 2630);
FORCEADD RES..2
(-4650 4400);
FORCEPROP 1 LASTPIN (-4650 4300) $PN 2
J 0
(-4645 4310);
DISPLAY 0.617021 (-4645 4310);
PAINT ORANGE (-4645 4310);
FORCEPROP 1 LASTPIN (-4650 4500) $PN 1
J 0
(-4645 4462);
DISPLAY 0.617021 (-4645 4462);
PAINT ORANGE (-4645 4462);
FORCEPROP 1 LAST WATTAGE 1/16W
J 0
(-4610 4375);
DISPLAY 0.617021 (-4610 4375);
PAINT SKYBLUE (-4610 4375);
FORCEPROP 1 LAST MATERIAL CHIP
J 0
(-4610 4325);
DISPLAY 0.617021 (-4610 4325);
PAINT SKYBLUE (-4610 4325);
FORCEPROP 1 LAST PACK_TYPE 0402
J 0
(-4610 4225);
DISPLAY 0.617021 (-4610 4225);
PAINT SKYBLUE (-4610 4225);
FORCEPROP 1 LAST PART_NUMBER G21796-026
J 0
(-4610 4275);
DISPLAY 0.617021 (-4610 4275);
PAINT BLUE (-4610 4275);
FORCEPROP 1 LAST TOLERANCE 1%
J 0
(-4605 4425);
DISPLAY 0.617021 (-4605 4425);
PAINT SKYBLUE (-4605 4425);
FORCEPROP 1 LAST VALUE 1.00K
J 0
(-4605 4475);
DISPLAY 0.617021 (-4605 4475);
PAINT SKYBLUE (-4605 4475);
FORCEPROP 1 LAST LOCATION R9N14
J 0
(-4605 4525);
DISPLAY 0.617021 (-4605 4525);
PAINT AQUA (-4605 4525);
FORCEPROP 2 LAST CDS_LIB mstr_discrete
J 0
(-4650 4400);
PAINT ORANGE (-4650 4400);
DISPLAY INVISIBLE (-4650 4400);
FORCEPROP 2 LAST CDS_LOCATION R9N14
J 0
(-4605 4525);
DISPLAY 0.617021 (-4605 4525);
PAINT AQUA (-4605 4525);
DISPLAY INVISIBLE (-4605 4525);
FORCEPROP 1 LAST PATH I120
J 0
(-4600 4575);
DISPLAY 0.978723 (-4600 4575);
PAINT WHITE (-4600 4575);
DISPLAY INVISIBLE (-4600 4575);
FORCEPROP 0 LAST ROOM BMC
J 0
(-4600 4625);
DISPLAY 0.617021 (-4600 4625);
PAINT ORANGE (-4600 4625);
DISPLAY INVISIBLE (-4600 4625);
FORCEPROP 2 LAST SEC 1
J 0
(-4600 4625);
PAINT MONO (-4600 4625);
DISPLAY INVISIBLE (-4600 4625);
FORCEPROP 2 LAST SEC_TYPE 0402
J 0
(-4600 4625);
DISPLAY 1.021277 (-4600 4625);
PAINT ORANGE (-4600 4625);
DISPLAY INVISIBLE (-4600 4625);
FORCEPROP 0 LAST BOM_COST SM_CONTROLLER
J 0
(-4600 4725);
DISPLAY 1.021277 (-4600 4725);
PAINT ORANGE (-4600 4725);
DISPLAY INVISIBLE (-4600 4725);
FORCEADD RES..2
(-6950 3525);
FORCEPROP 1 LASTPIN (-6950 3425) $PN 2
J 0
(-6945 3435);
DISPLAY 0.617021 (-6945 3435);
PAINT ORANGE (-6945 3435);
FORCEPROP 1 LAST PART_NUMBER G21497-005
J 0
(-7160 3525);
DISPLAY 0.617021 (-7160 3525);
PAINT BLUE (-7160 3525);
FORCEPROP 1 LAST TOLERANCE 5%
J 0
(-6905 3550);
DISPLAY 0.617021 (-6905 3550);
PAINT SKYBLUE (-6905 3550);
FORCEPROP 1 LAST MATERIAL CHIP
J 0
(-6910 3450);
DISPLAY 0.617021 (-6910 3450);
PAINT SKYBLUE (-6910 3450);
FORCEPROP 1 LAST WATTAGE 1/16W
J 0
(-6910 3500);
DISPLAY 0.617021 (-6910 3500);
PAINT SKYBLUE (-6910 3500);
FORCEPROP 1 LAST PACK_TYPE 0402
J 0
(-7110 3575);
DISPLAY 0.617021 (-7110 3575);
PAINT SKYBLUE (-7110 3575);
FORCEPROP 1 LASTPIN (-6950 3625) $PN 1
J 0
(-6945 3587);
DISPLAY 0.617021 (-6945 3587);
PAINT ORANGE (-6945 3587);
FORCEPROP 1 LAST VALUE 0.0
J 0
(-6905 3600);
DISPLAY 0.617021 (-6905 3600);
PAINT SKYBLUE (-6905 3600);
FORCEPROP 1 LAST LOCATION R9N15
J 0
(-6905 3650);
DISPLAY 0.617021 (-6905 3650);
PAINT AQUA (-6905 3650);
FORCEPROP 2 LAST CDS_LIB mstr_discrete
J 0
(-6950 3525);
PAINT ORANGE (-6950 3525);
DISPLAY INVISIBLE (-6950 3525);
FORCEPROP 2 LAST ROOM PVCCIN_CPU0_VR
J 0
(-7000 3625);
DISPLAY 1.361702 (-7000 3625);
PAINT ORANGE (-7000 3625);
DISPLAY INVISIBLE (-7000 3625);
FORCEPROP 2 LAST SEC_TYPE 0402
J 0
(-6900 3750);
DISPLAY 1.021277 (-6900 3750);
PAINT ORANGE (-6900 3750);
DISPLAY INVISIBLE (-6900 3750);
FORCEPROP 1 LAST PATH I122
J 0
(-6900 3700);
DISPLAY 0.978723 (-6900 3700);
PAINT WHITE (-6900 3700);
DISPLAY INVISIBLE (-6900 3700);
FORCEPROP 2 LAST CDS_LOCATION R9N15
J 0
(-6905 3650);
DISPLAY 0.617021 (-6905 3650);
PAINT AQUA (-6905 3650);
DISPLAY INVISIBLE (-6905 3650);
FORCEPROP 2 LAST SEC 1
J 0
(-6900 3750);
PAINT MONO (-6900 3750);
DISPLAY INVISIBLE (-6900 3750);
FORCEADD RES..2
(-6550 3525);
FORCEPROP 1 LAST PACK_TYPE 0402
J 0
(-6710 3575);
DISPLAY 0.617021 (-6710 3575);
PAINT SKYBLUE (-6710 3575);
FORCEPROP 1 LAST PART_NUMBER G21497-005
J 0
(-6760 3525);
DISPLAY 0.617021 (-6760 3525);
PAINT BLUE (-6760 3525);
FORCEPROP 1 LAST TOLERANCE 5%
J 0
(-6505 3550);
DISPLAY 0.617021 (-6505 3550);
PAINT SKYBLUE (-6505 3550);
FORCEPROP 1 LASTPIN (-6550 3425) $PN 2
J 0
(-6545 3435);
DISPLAY 0.617021 (-6545 3435);
PAINT ORANGE (-6545 3435);
FORCEPROP 1 LAST WATTAGE 1/16W
J 0
(-6510 3500);
DISPLAY 0.617021 (-6510 3500);
PAINT SKYBLUE (-6510 3500);
FORCEPROP 1 LAST MATERIAL CHIP
J 0
(-6510 3450);
DISPLAY 0.617021 (-6510 3450);
PAINT SKYBLUE (-6510 3450);
FORCEPROP 1 LASTPIN (-6550 3625) $PN 1
J 0
(-6545 3587);
DISPLAY 0.617021 (-6545 3587);
PAINT ORANGE (-6545 3587);
FORCEPROP 1 LAST VALUE 0.0
J 0
(-6505 3600);
DISPLAY 0.617021 (-6505 3600);
PAINT SKYBLUE (-6505 3600);
FORCEPROP 1 LAST LOCATION R9N17
J 0
(-6505 3650);
DISPLAY 0.617021 (-6505 3650);
PAINT AQUA (-6505 3650);
FORCEPROP 2 LAST CDS_LIB mstr_discrete
J 0
(-6550 3525);
PAINT ORANGE (-6550 3525);
DISPLAY INVISIBLE (-6550 3525);
FORCEPROP 2 LAST ROOM PVCCIN_CPU0_VR
J 0
(-6600 3625);
DISPLAY 1.361702 (-6600 3625);
PAINT ORANGE (-6600 3625);
DISPLAY INVISIBLE (-6600 3625);
FORCEPROP 1 LAST PATH I123
J 0
(-6500 3700);
DISPLAY 0.978723 (-6500 3700);
PAINT WHITE (-6500 3700);
DISPLAY INVISIBLE (-6500 3700);
FORCEPROP 2 LAST SEC_TYPE 0402
J 0
(-6500 3750);
DISPLAY 1.021277 (-6500 3750);
PAINT ORANGE (-6500 3750);
DISPLAY INVISIBLE (-6500 3750);
FORCEPROP 2 LAST CDS_LOCATION R9N17
J 0
(-6505 3650);
DISPLAY 0.617021 (-6505 3650);
PAINT AQUA (-6505 3650);
DISPLAY INVISIBLE (-6505 3650);
FORCEPROP 2 LAST SEC 1
J 0
(-6500 3750);
PAINT MONO (-6500 3750);
DISPLAY INVISIBLE (-6500 3750);
FORCEADD RES..2
(-6150 3550);
FORCEPROP 1 LAST PACK_TYPE 0402
J 0
(-6310 3600);
DISPLAY 0.617021 (-6310 3600);
PAINT SKYBLUE (-6310 3600);
FORCEPROP 1 LASTPIN (-6150 3650) $PN 1
J 0
(-6145 3612);
DISPLAY 0.617021 (-6145 3612);
PAINT ORANGE (-6145 3612);
FORCEPROP 1 LASTPIN (-6150 3450) $PN 2
J 0
(-6145 3460);
DISPLAY 0.617021 (-6145 3460);
PAINT ORANGE (-6145 3460);
FORCEPROP 1 LAST PART_NUMBER G21497-005
J 0
(-6360 3550);
DISPLAY 0.617021 (-6360 3550);
PAINT BLUE (-6360 3550);
FORCEPROP 1 LAST MATERIAL CHIP
J 0
(-6110 3475);
DISPLAY 0.617021 (-6110 3475);
PAINT SKYBLUE (-6110 3475);
FORCEPROP 1 LAST WATTAGE 1/16W
J 0
(-6110 3525);
DISPLAY 0.617021 (-6110 3525);
PAINT SKYBLUE (-6110 3525);
FORCEPROP 1 LAST TOLERANCE 5%
J 0
(-6105 3575);
DISPLAY 0.617021 (-6105 3575);
PAINT SKYBLUE (-6105 3575);
FORCEPROP 1 LAST VALUE 0.0
J 0
(-6105 3625);
DISPLAY 0.617021 (-6105 3625);
PAINT SKYBLUE (-6105 3625);
FORCEPROP 1 LAST LOCATION R9N12
J 0
(-6105 3675);
DISPLAY 0.617021 (-6105 3675);
PAINT AQUA (-6105 3675);
FORCEPROP 2 LAST CDS_LIB mstr_discrete
J 0
(-6150 3550);
PAINT ORANGE (-6150 3550);
DISPLAY INVISIBLE (-6150 3550);
FORCEPROP 2 LAST ROOM PVCCIN_CPU0_VR
J 0
(-6200 3650);
DISPLAY 1.361702 (-6200 3650);
PAINT ORANGE (-6200 3650);
DISPLAY INVISIBLE (-6200 3650);
FORCEPROP 1 LAST PATH I124
J 0
(-6100 3725);
DISPLAY 0.978723 (-6100 3725);
PAINT WHITE (-6100 3725);
DISPLAY INVISIBLE (-6100 3725);
FORCEPROP 2 LAST CDS_LOCATION R9N12
J 0
(-6105 3675);
DISPLAY 0.617021 (-6105 3675);
PAINT AQUA (-6105 3675);
DISPLAY INVISIBLE (-6105 3675);
FORCEPROP 2 LAST SEC_TYPE 0402
J 0
(-6100 3775);
DISPLAY 1.021277 (-6100 3775);
PAINT ORANGE (-6100 3775);
DISPLAY INVISIBLE (-6100 3775);
FORCEPROP 2 LAST SEC 1
J 0
(-6100 3775);
PAINT MONO (-6100 3775);
DISPLAY INVISIBLE (-6100 3775);
FORCEADD RES..2
(-5725 3550);
FORCEPROP 1 LAST PART_NUMBER G21497-005
J 0
(-5935 3550);
DISPLAY 0.617021 (-5935 3550);
PAINT BLUE (-5935 3550);
FORCEPROP 1 LASTPIN (-5725 3450) $PN 2
J 0
(-5720 3460);
DISPLAY 0.617021 (-5720 3460);
PAINT ORANGE (-5720 3460);
FORCEPROP 1 LAST PACK_TYPE 0402
J 0
(-5885 3600);
DISPLAY 0.617021 (-5885 3600);
PAINT SKYBLUE (-5885 3600);
FORCEPROP 1 LASTPIN (-5725 3650) $PN 1
J 0
(-5720 3612);
DISPLAY 0.617021 (-5720 3612);
PAINT ORANGE (-5720 3612);
FORCEPROP 1 LAST WATTAGE 1/16W
J 0
(-5685 3525);
DISPLAY 0.617021 (-5685 3525);
PAINT SKYBLUE (-5685 3525);
FORCEPROP 1 LAST MATERIAL CHIP
J 0
(-5685 3475);
DISPLAY 0.617021 (-5685 3475);
PAINT SKYBLUE (-5685 3475);
FORCEPROP 1 LAST TOLERANCE 5%
J 0
(-5680 3575);
DISPLAY 0.617021 (-5680 3575);
PAINT SKYBLUE (-5680 3575);
FORCEPROP 1 LAST VALUE 0.0
J 0
(-5680 3625);
DISPLAY 0.617021 (-5680 3625);
PAINT SKYBLUE (-5680 3625);
FORCEPROP 1 LAST LOCATION R9N10
J 0
(-5680 3675);
DISPLAY 0.617021 (-5680 3675);
PAINT AQUA (-5680 3675);
FORCEPROP 2 LAST CDS_LIB mstr_discrete
J 0
(-5725 3550);
PAINT ORANGE (-5725 3550);
DISPLAY INVISIBLE (-5725 3550);
FORCEPROP 2 LAST ROOM PVCCIN_CPU0_VR
J 0
(-5775 3650);
DISPLAY 1.361702 (-5775 3650);
PAINT ORANGE (-5775 3650);
DISPLAY INVISIBLE (-5775 3650);
FORCEPROP 2 LAST CDS_LOCATION R9N10
J 0
(-5680 3675);
DISPLAY 0.617021 (-5680 3675);
PAINT AQUA (-5680 3675);
DISPLAY INVISIBLE (-5680 3675);
FORCEPROP 1 LAST PATH I125
J 0
(-5675 3725);
DISPLAY 0.978723 (-5675 3725);
PAINT WHITE (-5675 3725);
DISPLAY INVISIBLE (-5675 3725);
FORCEPROP 2 LAST SEC 1
J 0
(-5675 3775);
PAINT MONO (-5675 3775);
DISPLAY INVISIBLE (-5675 3775);
FORCEPROP 2 LAST SEC_TYPE 0402
J 0
(-5675 3775);
DISPLAY 1.021277 (-5675 3775);
PAINT ORANGE (-5675 3775);
DISPLAY INVISIBLE (-5675 3775);
FORCEADD RES..2
(-5275 3550);
FORCEPROP 1 LASTPIN (-5275 3450) $PN 2
J 0
(-5270 3460);
DISPLAY 0.617021 (-5270 3460);
PAINT ORANGE (-5270 3460);
FORCEPROP 1 LAST PART_NUMBER G21497-005
J 0
(-5485 3550);
DISPLAY 0.617021 (-5485 3550);
PAINT BLUE (-5485 3550);
FORCEPROP 1 LAST TOLERANCE 5%
J 0
(-5230 3575);
DISPLAY 0.617021 (-5230 3575);
PAINT SKYBLUE (-5230 3575);
FORCEPROP 1 LAST PACK_TYPE 0402
J 0
(-5435 3600);
DISPLAY 0.617021 (-5435 3600);
PAINT SKYBLUE (-5435 3600);
FORCEPROP 1 LASTPIN (-5275 3650) $PN 1
J 0
(-5270 3612);
DISPLAY 0.617021 (-5270 3612);
PAINT ORANGE (-5270 3612);
FORCEPROP 1 LAST VALUE 0.0
J 0
(-5230 3625);
DISPLAY 0.617021 (-5230 3625);
PAINT SKYBLUE (-5230 3625);
FORCEPROP 1 LAST WATTAGE 1/16W
J 0
(-5235 3525);
DISPLAY 0.617021 (-5235 3525);
PAINT SKYBLUE (-5235 3525);
FORCEPROP 1 LAST MATERIAL CHIP
J 0
(-5235 3475);
DISPLAY 0.617021 (-5235 3475);
PAINT SKYBLUE (-5235 3475);
FORCEPROP 1 LAST LOCATION R9N9
J 0
(-5230 3675);
DISPLAY 0.617021 (-5230 3675);
PAINT AQUA (-5230 3675);
FORCEPROP 2 LAST CDS_LIB mstr_discrete
J 0
(-5275 3550);
PAINT ORANGE (-5275 3550);
DISPLAY INVISIBLE (-5275 3550);
FORCEPROP 2 LAST ROOM PVCCIN_CPU0_VR
J 0
(-5325 3650);
DISPLAY 1.361702 (-5325 3650);
PAINT ORANGE (-5325 3650);
DISPLAY INVISIBLE (-5325 3650);
FORCEPROP 1 LAST PATH I126
J 0
(-5225 3725);
DISPLAY 0.978723 (-5225 3725);
PAINT WHITE (-5225 3725);
DISPLAY INVISIBLE (-5225 3725);
FORCEPROP 2 LAST CDS_LOCATION R9N9
J 0
(-5230 3675);
DISPLAY 0.617021 (-5230 3675);
PAINT AQUA (-5230 3675);
DISPLAY INVISIBLE (-5230 3675);
FORCEPROP 2 LAST SEC 1
J 0
(-5225 3775);
PAINT MONO (-5225 3775);
DISPLAY INVISIBLE (-5225 3775);
FORCEPROP 2 LAST SEC_TYPE 0402
J 0
(-5225 3775);
DISPLAY 1.021277 (-5225 3775);
PAINT ORANGE (-5225 3775);
DISPLAY INVISIBLE (-5225 3775);
FORCEADD OFFPAGE..1
(-7500 3750);
FORCEPROP 2 LAST $XR0 206 
J 0
(-7752 3750);
DISPLAY 0.638298 (-7752 3750);
PAINT MONO (-7752 3750);
FORCEPROP 2 LAST ROOM PVCCIN_CPU1_VR
J 0
(-8050 3825);
DISPLAY 1.361702 (-8050 3825);
PAINT WHITE (-8050 3825);
DISPLAY INVISIBLE (-8050 3825);
FORCEPROP 2 LAST CDS_LIB mstr_standard
J 0
(-7500 3750);
PAINT ORANGE (-7500 3750);
DISPLAY INVISIBLE (-7500 3750);
FORCEPROP 2 LAST PATH I127
J 0
(-7450 3825);
DISPLAY 1.021277 (-7450 3825);
PAINT ORANGE (-7450 3825);
DISPLAY INVISIBLE (-7450 3825);
FORCEPROP 1 LAST OFFPAGE TRUE
J 0
(-7175 3625);
DISPLAY 1.170213 (-7175 3625);
PAINT GREEN (-7175 3625);
DISPLAY INVISIBLE (-7175 3625);
FORCEPROP 1 LAST COMMENT_BODY TRUE
J 0
(-7375 3650);
DISPLAY 1.170213 (-7375 3650);
PAINT PEACH (-7375 3650);
DISPLAY INVISIBLE (-7375 3650);
FORCEADD RES..1
(-6875 1350);
FORCEPROP 1 LASTPIN (-6975 1350) $PN 1
J 0
(-6963 1362);
DISPLAY 0.617021 (-6963 1362);
PAINT ORANGE (-6963 1362);
FORCEPROP 1 LAST VALUE 0.0
J 2
(-6975 1250);
DISPLAY 0.617021 (-6975 1250);
PAINT SKYBLUE (-6975 1250);
FORCEPROP 1 LAST WATTAGE 1/16W
J 2
(-6900 1200);
DISPLAY 0.617021 (-6900 1200);
PAINT SKYBLUE (-6900 1200);
FORCEPROP 1 LAST TOLERANCE 5%
J 0
(-6925 1250);
DISPLAY 0.617021 (-6925 1250);
PAINT SKYBLUE (-6925 1250);
FORCEPROP 1 LAST PART_NUMBER G21497-005
J 0
(-7025 1300);
DISPLAY 0.617021 (-7025 1300);
PAINT BLUE (-7025 1300);
FORCEPROP 1 LAST LOCATION R9N5
J 0
(-6925 1400);
DISPLAY 0.617021 (-6925 1400);
PAINT AQUA (-6925 1400);
FORCEPROP 1 LAST PACK_TYPE 0402
J 0
(-6800 1250);
DISPLAY 0.617021 (-6800 1250);
PAINT SKYBLUE (-6800 1250);
FORCEPROP 1 LAST MATERIAL CHIP
J 0
(-6875 1200);
DISPLAY 0.617021 (-6875 1200);
PAINT SKYBLUE (-6875 1200);
FORCEPROP 1 LASTPIN (-6775 1350) $PN 2
J 0
(-6813 1362);
DISPLAY 0.617021 (-6813 1362);
PAINT ORANGE (-6813 1362);
FORCEPROP 2 LAST CDS_LOCATION R9N5
J 0
(-6925 1400);
DISPLAY 0.617021 (-6925 1400);
PAINT AQUA (-6925 1400);
DISPLAY INVISIBLE (-6925 1400);
FORCEPROP 2 LAST ROOM PVCCIN_CPU0_VR
J 0
(-6925 1450);
DISPLAY 1.361702 (-6925 1450);
PAINT ORANGE (-6925 1450);
DISPLAY INVISIBLE (-6925 1450);
FORCEPROP 2 LAST CDS_LIB mstr_discrete
J 0
(-6875 1350);
PAINT ORANGE (-6875 1350);
DISPLAY INVISIBLE (-6875 1350);
FORCEPROP 1 LAST PATH I128
J 0
(-6925 1500);
DISPLAY 0.978723 (-6925 1500);
PAINT WHITE (-6925 1500);
DISPLAY INVISIBLE (-6925 1500);
FORCEPROP 2 LAST SEC_TYPE 0402
J 0
(-6925 1550);
DISPLAY 1.021277 (-6925 1550);
PAINT ORANGE (-6925 1550);
DISPLAY INVISIBLE (-6925 1550);
FORCEPROP 2 LAST SEC 1
J 0
(-6925 1550);
PAINT MONO (-6925 1550);
DISPLAY INVISIBLE (-6925 1550);
FORCEADD OFFPAGE..1
(-7725 1350);
FORCEPROP 2 LAST $XR0 206 
J 0
(-7977 1350);
DISPLAY 0.638298 (-7977 1350);
PAINT MONO (-7977 1350);
FORCEPROP 2 LAST ROOM PVCCIN_CPU1_VR
J 0
(-8275 1425);
DISPLAY 1.361702 (-8275 1425);
PAINT WHITE (-8275 1425);
DISPLAY INVISIBLE (-8275 1425);
FORCEPROP 2 LAST CDS_LIB mstr_standard
J 0
(-7725 1350);
PAINT ORANGE (-7725 1350);
DISPLAY INVISIBLE (-7725 1350);
FORCEPROP 2 LAST PATH I129
J 0
(-7675 1425);
DISPLAY 1.021277 (-7675 1425);
PAINT ORANGE (-7675 1425);
DISPLAY INVISIBLE (-7675 1425);
FORCEPROP 1 LAST OFFPAGE TRUE
J 0
(-7400 1225);
DISPLAY 1.170213 (-7400 1225);
PAINT GREEN (-7400 1225);
DISPLAY INVISIBLE (-7400 1225);
FORCEPROP 1 LAST COMMENT_BODY TRUE
J 0
(-7600 1250);
DISPLAY 1.170213 (-7600 1250);
PAINT PEACH (-7600 1250);
DISPLAY INVISIBLE (-7600 1250);
FORCEADD OFFPAGE..2
(-1150 2575);
FORCEPROP 2 LAST $XR0 210 
J 0
(-961 2575);
DISPLAY 0.638298 (-961 2575);
PAINT MONO (-961 2575);
FORCEPROP 2 LAST ROOM PVCCIN_CPU1_VR
J 0
(-1575 2650);
DISPLAY 1.361702 (-1575 2650);
PAINT WHITE (-1575 2650);
DISPLAY INVISIBLE (-1575 2650);
FORCEPROP 2 LAST CDS_LIB mstr_standard
J 0
(-1150 2575);
PAINT ORANGE (-1150 2575);
DISPLAY INVISIBLE (-1150 2575);
FORCEPROP 2 LAST PATH I13
J 0
(-975 2650);
DISPLAY 1.021277 (-975 2650);
PAINT ORANGE (-975 2650);
DISPLAY INVISIBLE (-975 2650);
FORCEPROP 1 LAST OFFPAGE TRUE
J 0
(-825 2450);
DISPLAY 1.170213 (-825 2450);
PAINT GREEN (-825 2450);
DISPLAY INVISIBLE (-825 2450);
FORCEPROP 1 LAST COMMENT_BODY TRUE
J 0
(-1195 2480);
DISPLAY 1.170213 (-1195 2480);
PAINT PEACH (-1195 2480);
DISPLAY INVISIBLE (-1195 2480);
FORCEADD PXE1610B..1
(-3825 2625);
FORCEPROP 2 LASTPIN (-4275 1775) $PN 41
J 2
(-4285 1785);
DISPLAY 0.617021 (-4285 1785);
PAINT ORANGE (-4285 1785);
FORCEPROP 2 LASTPIN (-4275 1925) $PN 37
J 2
(-4285 1935);
DISPLAY 0.617021 (-4285 1935);
PAINT ORANGE (-4285 1935);
FORCEPROP 2 LASTPIN (-4275 1875) $PN 38
J 2
(-4285 1885);
DISPLAY 0.617021 (-4285 1885);
PAINT ORANGE (-4285 1885);
FORCEPROP 2 LASTPIN (-4275 1975) $PN 42
J 2
(-4285 1985);
DISPLAY 0.617021 (-4285 1985);
PAINT ORANGE (-4285 1985);
FORCEPROP 2 LASTPIN (-4275 1825) $PN 44
J 2
(-4285 1835);
DISPLAY 0.617021 (-4285 1835);
PAINT ORANGE (-4285 1835);
FORCEPROP 2 LASTPIN (-4275 2075) $PN 10
J 2
(-4285 2085);
DISPLAY 0.617021 (-4285 2085);
PAINT ORANGE (-4285 2085);
FORCEPROP 2 LASTPIN (-4275 2175) $PN 46
J 2
(-4285 2185);
DISPLAY 0.617021 (-4285 2185);
PAINT ORANGE (-4285 2185);
FORCEPROP 2 LASTPIN (-4275 2225) $PN 45
J 2
(-4285 2235);
DISPLAY 0.617021 (-4285 2235);
PAINT ORANGE (-4285 2235);
FORCEPROP 2 LASTPIN (-4275 2275) $PN 12
J 2
(-4285 2285);
DISPLAY 0.617021 (-4285 2285);
PAINT ORANGE (-4285 2285);
FORCEPROP 2 LASTPIN (-4275 2325) $PN 43
J 2
(-4285 2335);
DISPLAY 0.617021 (-4285 2335);
PAINT ORANGE (-4285 2335);
FORCEPROP 2 LASTPIN (-4275 2425) $PN 36
J 2
(-4285 2435);
DISPLAY 0.617021 (-4285 2435);
PAINT ORANGE (-4285 2435);
FORCEPROP 2 LASTPIN (-4275 2475) $PN 35
J 2
(-4285 2485);
DISPLAY 0.617021 (-4285 2485);
PAINT ORANGE (-4285 2485);
FORCEPROP 2 LASTPIN (-4275 2525) $PN 22
J 2
(-4285 2535);
DISPLAY 0.617021 (-4285 2535);
PAINT ORANGE (-4285 2535);
FORCEPROP 2 LASTPIN (-4275 2775) $PN 30
J 2
(-4285 2785);
DISPLAY 0.617021 (-4285 2785);
PAINT ORANGE (-4285 2785);
FORCEPROP 2 LASTPIN (-4275 2725) $PN 32
J 2
(-4285 2735);
DISPLAY 0.617021 (-4285 2735);
PAINT ORANGE (-4285 2735);
FORCEPROP 2 LASTPIN (-4275 2675) $PN 34
J 2
(-4285 2685);
DISPLAY 0.617021 (-4285 2685);
PAINT ORANGE (-4285 2685);
FORCEPROP 2 LASTPIN (-4275 2575) $PN 21
J 2
(-4285 2585);
DISPLAY 0.617021 (-4285 2585);
PAINT ORANGE (-4285 2585);
FORCEPROP 2 LASTPIN (-4275 2875) $PN 26
J 2
(-4285 2885);
DISPLAY 0.617021 (-4285 2885);
PAINT ORANGE (-4285 2885);
FORCEPROP 2 LASTPIN (-4275 2825) $PN 28
J 2
(-4285 2835);
DISPLAY 0.617021 (-4285 2835);
PAINT ORANGE (-4285 2835);
FORCEPROP 2 LASTPIN (-4275 2925) $PN 24
J 2
(-4285 2935);
DISPLAY 0.617021 (-4285 2935);
PAINT ORANGE (-4285 2935);
FORCEPROP 2 LASTPIN (-4275 3025) $PN 31
J 2
(-4285 3035);
DISPLAY 0.617021 (-4285 3035);
PAINT ORANGE (-4285 3035);
FORCEPROP 2 LASTPIN (-4275 2975) $PN 33
J 2
(-4285 2985);
DISPLAY 0.617021 (-4285 2985);
PAINT ORANGE (-4285 2985);
FORCEPROP 2 LASTPIN (-4275 3125) $PN 27
J 2
(-4285 3135);
DISPLAY 0.617021 (-4285 3135);
PAINT ORANGE (-4285 3135);
FORCEPROP 2 LASTPIN (-4275 3075) $PN 29
J 2
(-4285 3085);
DISPLAY 0.617021 (-4285 3085);
PAINT ORANGE (-4285 3085);
FORCEPROP 2 LASTPIN (-4275 3175) $PN 25
J 2
(-4285 3185);
DISPLAY 0.617021 (-4285 3185);
PAINT ORANGE (-4285 3185);
FORCEPROP 2 LASTPIN (-4275 3225) $PN 23
J 2
(-4285 3235);
DISPLAY 0.617021 (-4285 3235);
PAINT ORANGE (-4285 3235);
FORCEPROP 2 LASTPIN (-4275 3325) $PN 17
J 2
(-4285 3335);
DISPLAY 0.617021 (-4285 3335);
PAINT ORANGE (-4285 3335);
FORCEPROP 2 LASTPIN (-4275 3425) $PN 47
J 2
(-4285 3435);
DISPLAY 0.617021 (-4285 3435);
PAINT ORANGE (-4285 3435);
FORCEPROP 1 LAST MATERIAL IC
J 0
(-4225 3550);
DISPLAY 0.617021 (-4225 3550);
PAINT SKYBLUE (-4225 3550);
FORCEPROP 1 LAST PART_NUMBER H79206-001
J 0
(-4225 1675);
DISPLAY 0.617021 (-4225 1675);
PAINT BLUE (-4225 1675);
FORCEPROP 1 LAST LOCATION EU1C2
J 0
(-4225 3600);
DISPLAY 0.617021 (-4225 3600);
PAINT AQUA (-4225 3600);
FORCEPROP 2 LASTPIN (-3375 1875) $PN 49
J 0
(-3365 1885);
DISPLAY 0.617021 (-3365 1885);
PAINT ORANGE (-3365 1885);
FORCEPROP 2 LASTPIN (-3375 2075) $PN 9
J 0
(-3365 2085);
DISPLAY 0.617021 (-3365 2085);
PAINT ORANGE (-3365 2085);
FORCEPROP 2 LASTPIN (-3375 2175) $PN 8
J 0
(-3365 2185);
DISPLAY 0.617021 (-3365 2185);
PAINT ORANGE (-3365 2185);
FORCEPROP 2 LASTPIN (-3375 2275) $PN 2
J 0
(-3365 2285);
DISPLAY 0.617021 (-3365 2285);
PAINT ORANGE (-3365 2285);
FORCEPROP 2 LASTPIN (-3375 2375) $PN 4
J 0
(-3365 2385);
DISPLAY 0.617021 (-3365 2385);
PAINT ORANGE (-3365 2385);
FORCEPROP 2 LASTPIN (-3375 2325) $PN 3
J 0
(-3365 2335);
DISPLAY 0.617021 (-3365 2335);
PAINT ORANGE (-3365 2335);
FORCEPROP 2 LASTPIN (-3375 2475) $PN 6
J 0
(-3365 2485);
DISPLAY 0.617021 (-3365 2485);
PAINT ORANGE (-3365 2485);
FORCEPROP 2 LASTPIN (-3375 2425) $PN 5
J 0
(-3365 2435);
DISPLAY 0.617021 (-3365 2435);
PAINT ORANGE (-3365 2435);
FORCEPROP 2 LASTPIN (-3375 2525) $PN 7
J 0
(-3365 2535);
DISPLAY 0.617021 (-3365 2535);
PAINT ORANGE (-3365 2535);
FORCEPROP 2 LASTPIN (-3375 2575) $PN 1
J 0
(-3365 2585);
DISPLAY 0.617021 (-3365 2585);
PAINT ORANGE (-3365 2585);
FORCEPROP 2 LASTPIN (-3375 2725) $PN 15
J 0
(-3365 2735);
DISPLAY 0.617021 (-3365 2735);
PAINT ORANGE (-3365 2735);
FORCEPROP 2 LASTPIN (-3375 2675) $PN 16
J 0
(-3365 2685);
DISPLAY 0.617021 (-3365 2685);
PAINT ORANGE (-3365 2685);
FORCEPROP 2 LASTPIN (-3375 2925) $PN 19
J 0
(-3365 2935);
DISPLAY 0.617021 (-3365 2935);
PAINT ORANGE (-3365 2935);
FORCEPROP 2 LASTPIN (-3375 2825) $PN 48
J 0
(-3365 2835);
DISPLAY 0.617021 (-3365 2835);
PAINT ORANGE (-3365 2835);
FORCEPROP 2 LASTPIN (-3375 2775) $PN 18
J 0
(-3365 2785);
DISPLAY 0.617021 (-3365 2785);
PAINT ORANGE (-3365 2785);
FORCEPROP 2 LASTPIN (-3375 3025) $PN 13
J 0
(-3365 3035);
DISPLAY 0.617021 (-3365 3035);
PAINT ORANGE (-3365 3035);
FORCEPROP 2 LASTPIN (-3375 3375) $PN 11
J 0
(-3365 3385);
DISPLAY 0.617021 (-3365 3385);
PAINT ORANGE (-3365 3385);
FORCEPROP 2 LASTPIN (-3375 3325) $PN 20
J 0
(-3365 3335);
DISPLAY 0.617021 (-3365 3335);
PAINT ORANGE (-3365 3335);
FORCEPROP 2 LASTPIN (-3375 3175) $PN 39
J 0
(-3365 3185);
DISPLAY 0.617021 (-3365 3185);
PAINT ORANGE (-3365 3185);
FORCEPROP 2 LASTPIN (-3375 3125) $PN 40
J 0
(-3365 3135);
DISPLAY 0.617021 (-3365 3135);
PAINT ORANGE (-3365 3135);
FORCEPROP 2 LASTPIN (-3375 3275) $PN 14
J 0
(-3365 3285);
DISPLAY 0.617021 (-3365 3285);
PAINT ORANGE (-3365 3285);
FORCEPROP 2 LAST CDS_LOCATION EU1C2
J 0
(-4225 3600);
DISPLAY 0.617021 (-4225 3600);
PAINT AQUA (-4225 3600);
DISPLAY INVISIBLE (-4225 3600);
FORCEPROP 2 LAST SEC 1
J 0
(-4225 3650);
DISPLAY 0.680851 (-4225 3650);
PAINT MONO (-4225 3650);
DISPLAY INVISIBLE (-4225 3650);
FORCEPROP 2 LAST SEC_TYPE QFN
J 0
(-4225 3650);
DISPLAY 1.021277 (-4225 3650);
PAINT ORANGE (-4225 3650);
DISPLAY INVISIBLE (-4225 3650);
FORCEPROP 1 LAST PACK_TYPE QFN
J 0
(-4225 3650);
PAINT SKYBLUE (-4225 3650);
DISPLAY INVISIBLE (-4225 3650);
FORCEPROP 1 LAST CDS_LMAN_SYM_OUTLINE -400,900,400,-900
J 0
(-3825 2625);
DISPLAY 0.468085 (-3825 2625);
PAINT GREEN (-3825 2625);
DISPLAY INVISIBLE (-3825 2625);
FORCEPROP 2 LAST CDS_LIB mstr_controller
J 0
(-3825 2625);
PAINT ORANGE (-3825 2625);
DISPLAY INVISIBLE (-3825 2625);
FORCEPROP 1 LAST PATH I130
J 0
(-3725 3551);
PAINT WHITE (-3725 3551);
DISPLAY INVISIBLE (-3725 3551);
FORCEADD OFFPAGE..2
(-1150 2475);
FORCEPROP 2 LAST $XR0 207 
J 0
(-961 2475);
DISPLAY 0.638298 (-961 2475);
PAINT MONO (-961 2475);
FORCEPROP 2 LAST ROOM PVCCIN_CPU1_VR
J 0
(-1575 2550);
DISPLAY 1.361702 (-1575 2550);
PAINT WHITE (-1575 2550);
DISPLAY INVISIBLE (-1575 2550);
FORCEPROP 2 LAST CDS_LIB mstr_standard
J 0
(-1150 2475);
PAINT ORANGE (-1150 2475);
DISPLAY INVISIBLE (-1150 2475);
FORCEPROP 2 LAST PATH I14
J 0
(-950 2525);
DISPLAY 1.021277 (-950 2525);
PAINT ORANGE (-950 2525);
DISPLAY INVISIBLE (-950 2525);
FORCEPROP 1 LAST OFFPAGE TRUE
J 0
(-825 2350);
DISPLAY 1.170213 (-825 2350);
PAINT GREEN (-825 2350);
DISPLAY INVISIBLE (-825 2350);
FORCEPROP 1 LAST COMMENT_BODY TRUE
J 0
(-1195 2380);
DISPLAY 1.170213 (-1195 2380);
PAINT PEACH (-1195 2380);
DISPLAY INVISIBLE (-1195 2380);
FORCEADD OFFPAGE..2
(-1150 2525);
FORCEPROP 2 LAST $XR0 207 
J 0
(-961 2525);
DISPLAY 0.638298 (-961 2525);
PAINT MONO (-961 2525);
FORCEPROP 2 LAST ROOM PVCCIN_CPU1_VR
J 0
(-1575 2600);
DISPLAY 1.361702 (-1575 2600);
PAINT WHITE (-1575 2600);
DISPLAY INVISIBLE (-1575 2600);
FORCEPROP 2 LAST CDS_LIB mstr_standard
J 0
(-1150 2525);
PAINT ORANGE (-1150 2525);
DISPLAY INVISIBLE (-1150 2525);
FORCEPROP 2 LAST PATH I15
J 0
(-950 2575);
DISPLAY 1.021277 (-950 2575);
PAINT ORANGE (-950 2575);
DISPLAY INVISIBLE (-950 2575);
FORCEPROP 1 LAST OFFPAGE TRUE
J 0
(-825 2400);
DISPLAY 1.170213 (-825 2400);
PAINT GREEN (-825 2400);
DISPLAY INVISIBLE (-825 2400);
FORCEPROP 1 LAST COMMENT_BODY TRUE
J 0
(-1195 2430);
DISPLAY 1.170213 (-1195 2430);
PAINT PEACH (-1195 2430);
DISPLAY INVISIBLE (-1195 2430);
FORCEADD OFFPAGE..2
(-1150 2375);
FORCEPROP 2 LAST $XR0 208 
J 0
(-961 2375);
DISPLAY 0.638298 (-961 2375);
PAINT MONO (-961 2375);
FORCEPROP 2 LAST ROOM PVCCIN_CPU1_VR
J 0
(-1575 2450);
DISPLAY 1.361702 (-1575 2450);
PAINT WHITE (-1575 2450);
DISPLAY INVISIBLE (-1575 2450);
FORCEPROP 2 LAST CDS_LIB mstr_standard
J 0
(-1150 2375);
PAINT ORANGE (-1150 2375);
DISPLAY INVISIBLE (-1150 2375);
FORCEPROP 2 LAST PATH I16
J 0
(-950 2425);
DISPLAY 1.021277 (-950 2425);
PAINT ORANGE (-950 2425);
DISPLAY INVISIBLE (-950 2425);
FORCEPROP 1 LAST OFFPAGE TRUE
J 0
(-825 2250);
DISPLAY 1.170213 (-825 2250);
PAINT GREEN (-825 2250);
DISPLAY INVISIBLE (-825 2250);
FORCEPROP 1 LAST COMMENT_BODY TRUE
J 0
(-1195 2280);
DISPLAY 1.170213 (-1195 2280);
PAINT PEACH (-1195 2280);
DISPLAY INVISIBLE (-1195 2280);
FORCEADD OFFPAGE..2
(-1150 2425);
FORCEPROP 2 LAST $XR0 208 
J 0
(-961 2425);
DISPLAY 0.638298 (-961 2425);
PAINT MONO (-961 2425);
FORCEPROP 2 LAST ROOM PVCCIN_CPU1_VR
J 0
(-1575 2500);
DISPLAY 1.361702 (-1575 2500);
PAINT WHITE (-1575 2500);
DISPLAY INVISIBLE (-1575 2500);
FORCEPROP 2 LAST CDS_LIB mstr_standard
J 0
(-1150 2425);
PAINT ORANGE (-1150 2425);
DISPLAY INVISIBLE (-1150 2425);
FORCEPROP 2 LAST PATH I17
J 0
(-950 2475);
DISPLAY 1.021277 (-950 2475);
PAINT ORANGE (-950 2475);
DISPLAY INVISIBLE (-950 2475);
FORCEPROP 1 LAST OFFPAGE TRUE
J 0
(-825 2300);
DISPLAY 1.170213 (-825 2300);
PAINT GREEN (-825 2300);
DISPLAY INVISIBLE (-825 2300);
FORCEPROP 1 LAST COMMENT_BODY TRUE
J 0
(-1195 2330);
DISPLAY 1.170213 (-1195 2330);
PAINT PEACH (-1195 2330);
DISPLAY INVISIBLE (-1195 2330);
FORCEADD OFFPAGE..2
(-1150 2325);
FORCEPROP 2 LAST $XR0 209 
J 0
(-961 2325);
DISPLAY 0.638298 (-961 2325);
PAINT MONO (-961 2325);
FORCEPROP 2 LAST ROOM PVCCIN_CPU1_VR
J 0
(-1575 2400);
DISPLAY 1.361702 (-1575 2400);
PAINT WHITE (-1575 2400);
DISPLAY INVISIBLE (-1575 2400);
FORCEPROP 2 LAST CDS_LIB mstr_standard
J 0
(-1150 2325);
PAINT ORANGE (-1150 2325);
DISPLAY INVISIBLE (-1150 2325);
FORCEPROP 2 LAST PATH I18
J 0
(-975 2400);
DISPLAY 1.021277 (-975 2400);
PAINT ORANGE (-975 2400);
DISPLAY INVISIBLE (-975 2400);
FORCEPROP 1 LAST OFFPAGE TRUE
J 0
(-825 2200);
DISPLAY 1.170213 (-825 2200);
PAINT GREEN (-825 2200);
DISPLAY INVISIBLE (-825 2200);
FORCEPROP 1 LAST COMMENT_BODY TRUE
J 0
(-1195 2230);
DISPLAY 1.170213 (-1195 2230);
PAINT PEACH (-1195 2230);
DISPLAY INVISIBLE (-1195 2230);
FORCEADD OFFPAGE..3
(-850 1775);
FORCEPROP 2 LAST $XR0 138 
J 0
(-636 1775);
DISPLAY 0.638298 (-636 1775);
PAINT MONO (-636 1775);
FORCEPROP 2 LAST $XR1 159 
J 0
(-516 1775);
DISPLAY 0.638298 (-516 1775);
PAINT MONO (-516 1775);
FORCEPROP 2 LAST $XR2 193 
J 0
(-396 1775);
DISPLAY 0.638298 (-396 1775);
PAINT MONO (-396 1775);
FORCEPROP 2 LAST $XR3 194 
J 0
(-276 1775);
DISPLAY 0.638298 (-276 1775);
PAINT MONO (-276 1775);
FORCEPROP 2 LAST $XR4 201 
J 0
(-636 1739);
DISPLAY 0.638298 (-636 1739);
PAINT MONO (-636 1739);
FORCEPROP 2 LAST $XR5 211 
J 0
(-516 1739);
DISPLAY 0.638298 (-516 1739);
PAINT MONO (-516 1739);
FORCEPROP 2 LAST $XR6 213 
J 0
(-396 1739);
DISPLAY 0.638298 (-396 1739);
PAINT MONO (-396 1739);
FORCEPROP 2 LAST $XR7 215 
J 0
(-276 1739);
DISPLAY 0.638298 (-276 1739);
PAINT MONO (-276 1739);
FORCEPROP 2 LAST $XR8 218 
J 0
(-636 1811);
DISPLAY 0.638298 (-636 1811);
PAINT MONO (-636 1811);
FORCEPROP 2 LAST $XR9 223 
J 0
(-516 1811);
DISPLAY 0.638298 (-516 1811);
PAINT MONO (-516 1811);
FORCEPROP 2 LAST $XR10 226 
J 0
(-396 1811);
DISPLAY 0.638298 (-396 1811);
PAINT MONO (-396 1811);
FORCEPROP 2 LAST $XR11 235 
J 0
(-276 1811);
DISPLAY 0.638298 (-276 1811);
PAINT MONO (-276 1811);
FORCEPROP 2 LAST ROOM PVCCIN_CPU1_VR
J 0
(-1250 1850);
DISPLAY 1.361702 (-1250 1850);
PAINT WHITE (-1250 1850);
DISPLAY INVISIBLE (-1250 1850);
FORCEPROP 2 LAST CDS_LIB mstr_standard
J 0
(-850 1775);
PAINT ORANGE (-850 1775);
DISPLAY INVISIBLE (-850 1775);
FORCEPROP 2 LAST PATH I23
J 0
(-275 1825);
DISPLAY 1.021277 (-275 1825);
PAINT ORANGE (-275 1825);
DISPLAY INVISIBLE (-275 1825);
FORCEPROP 1 LAST OFFPAGE TRUE
J 0
(-525 1650);
DISPLAY 1.170213 (-525 1650);
PAINT GREEN (-525 1650);
DISPLAY INVISIBLE (-525 1650);
FORCEPROP 1 LAST COMMENT_BODY TRUE
J 0
(-900 1675);
DISPLAY 1.170213 (-900 1675);
PAINT PEACH (-900 1675);
DISPLAY INVISIBLE (-900 1675);
FORCEADD OFFPAGE..1
R 2
(-850 1525);
FORCEPROP 2 LAST $XR0 138 
J 0
(-664 1525);
DISPLAY 0.638298 (-664 1525);
PAINT MONO (-664 1525);
FORCEPROP 2 LAST $XR1 159 
J 0
(-544 1525);
DISPLAY 0.638298 (-544 1525);
PAINT MONO (-544 1525);
FORCEPROP 2 LAST $XR2 211 
J 0
(-424 1525);
DISPLAY 0.638298 (-424 1525);
PAINT MONO (-424 1525);
FORCEPROP 2 LAST $XR3 213 
J 0
(-304 1525);
DISPLAY 0.638298 (-304 1525);
PAINT MONO (-304 1525);
FORCEPROP 2 LAST $XR4 235 
J 0
(-664 1489);
DISPLAY 0.638298 (-664 1489);
PAINT MONO (-664 1489);
FORCEPROP 2 LAST $XR5 193 
J 0
(-544 1489);
DISPLAY 0.638298 (-544 1489);
PAINT MONO (-544 1489);
FORCEPROP 2 LAST $XR6 194 
J 0
(-424 1489);
DISPLAY 0.638298 (-424 1489);
PAINT MONO (-424 1489);
FORCEPROP 2 LAST $XR7 201 
J 0
(-304 1489);
DISPLAY 0.638298 (-304 1489);
PAINT MONO (-304 1489);
FORCEPROP 2 LAST $XR8 215 
J 0
(-664 1561);
DISPLAY 0.638298 (-664 1561);
PAINT MONO (-664 1561);
FORCEPROP 2 LAST $XR9 218 
J 0
(-544 1561);
DISPLAY 0.638298 (-544 1561);
PAINT MONO (-544 1561);
FORCEPROP 2 LAST $XR10 223 
J 0
(-424 1561);
DISPLAY 0.638298 (-424 1561);
PAINT MONO (-424 1561);
FORCEPROP 2 LAST $XR11 226 
J 0
(-304 1561);
DISPLAY 0.638298 (-304 1561);
PAINT MONO (-304 1561);
FORCEPROP 2 LAST ROOM PVCCIN_CPU1_VR
J 0
(-1275 1600);
DISPLAY 1.361702 (-1275 1600);
PAINT WHITE (-1275 1600);
DISPLAY INVISIBLE (-1275 1600);
FORCEPROP 2 LAST CDS_LIB mstr_standard
J 0
(-850 1525);
PAINT ORANGE (-850 1525);
DISPLAY INVISIBLE (-850 1525);
FORCEPROP 2 LAST PATH I24
J 0
(-300 1575);
DISPLAY 1.021277 (-300 1575);
PAINT ORANGE (-300 1575);
DISPLAY INVISIBLE (-300 1575);
FORCEPROP 1 LAST OFFPAGE TRUE
J 2
(-1175 1400);
DISPLAY 1.170213 (-1175 1400);
PAINT GREEN (-1175 1400);
DISPLAY INVISIBLE (-1175 1400);
FORCEPROP 1 LAST COMMENT_BODY TRUE
J 2
(-975 1425);
DISPLAY 1.170213 (-975 1425);
PAINT PEACH (-975 1425);
DISPLAY INVISIBLE (-975 1425);
FORCEADD OFFPAGE..1
R 2
(-950 1175);
FORCEPROP 2 LAST $XR0 206 
J 0
(-764 1175);
DISPLAY 0.638298 (-764 1175);
PAINT MONO (-764 1175);
FORCEPROP 2 LAST ROOM PVCCIN_CPU1_VR
J 0
(-1375 1250);
DISPLAY 1.361702 (-1375 1250);
PAINT WHITE (-1375 1250);
DISPLAY INVISIBLE (-1375 1250);
FORCEPROP 2 LAST CDS_LIB mstr_standard
J 2
(-950 1175);
PAINT ORANGE (-950 1175);
DISPLAY INVISIBLE (-950 1175);
FORCEPROP 2 LAST PATH I26
J 0
(-750 1225);
DISPLAY 1.021277 (-750 1225);
PAINT ORANGE (-750 1225);
DISPLAY INVISIBLE (-750 1225);
FORCEPROP 1 LAST OFFPAGE TRUE
J 2
(-1275 1050);
DISPLAY 1.170213 (-1275 1050);
PAINT GREEN (-1275 1050);
DISPLAY INVISIBLE (-1275 1050);
FORCEPROP 1 LAST COMMENT_BODY TRUE
J 2
(-1075 1075);
DISPLAY 1.170213 (-1075 1075);
PAINT PEACH (-1075 1075);
DISPLAY INVISIBLE (-1075 1075);
FORCEADD RES..1
(-2000 1775);
FORCEPROP 1 LASTPIN (-2100 1775) $PN 1
J 0
(-2088 1787);
DISPLAY 0.617021 (-2088 1787);
PAINT WHITE (-2088 1787);
FORCEPROP 1 LAST VALUE 0.0
J 2
(-2100 1675);
DISPLAY 0.617021 (-2100 1675);
PAINT SKYBLUE (-2100 1675);
FORCEPROP 1 LAST WATTAGE 1/16W
J 2
(-2025 1625);
DISPLAY 0.617021 (-2025 1625);
PAINT SKYBLUE (-2025 1625);
FORCEPROP 1 LAST TOLERANCE 5%
J 0
(-2050 1675);
DISPLAY 0.617021 (-2050 1675);
PAINT SKYBLUE (-2050 1675);
FORCEPROP 1 LAST PART_NUMBER G21497-005
J 0
(-2150 1725);
DISPLAY 0.617021 (-2150 1725);
PAINT BLUE (-2150 1725);
FORCEPROP 1 LAST LOCATION R1C23
J 0
(-2050 1825);
DISPLAY 0.617021 (-2050 1825);
PAINT AQUA (-2050 1825);
FORCEPROP 1 LASTPIN (-1900 1775) $PN 2
J 0
(-1938 1787);
DISPLAY 0.617021 (-1938 1787);
PAINT WHITE (-1938 1787);
FORCEPROP 1 LAST MATERIAL CHIP
J 0
(-2000 1625);
DISPLAY 0.617021 (-2000 1625);
PAINT SKYBLUE (-2000 1625);
FORCEPROP 1 LAST PACK_TYPE 0402
J 0
(-1925 1675);
DISPLAY 0.617021 (-1925 1675);
PAINT SKYBLUE (-1925 1675);
FORCEPROP 2 LAST SEC_TYPE 0402
J 0
(-2050 1975);
DISPLAY 1.021277 (-2050 1975);
PAINT ORANGE (-2050 1975);
DISPLAY INVISIBLE (-2050 1975);
FORCEPROP 2 LAST SEC 1
J 0
(-2050 1975);
DISPLAY 0.680851 (-2050 1975);
PAINT MONO (-2050 1975);
DISPLAY INVISIBLE (-2050 1975);
FORCEPROP 2 LAST CDS_LOCATION R1C23
J 0
(-2050 1825);
DISPLAY 0.617021 (-2050 1825);
PAINT AQUA (-2050 1825);
DISPLAY INVISIBLE (-2050 1825);
FORCEPROP 1 LAST PATH I27
J 0
(-2050 1925);
DISPLAY 0.978723 (-2050 1925);
PAINT WHITE (-2050 1925);
DISPLAY INVISIBLE (-2050 1925);
FORCEPROP 2 LAST ROOM PVCCIN_CPU1_VR
J 0
(-2050 1875);
DISPLAY 1.361702 (-2050 1875);
PAINT WHITE (-2050 1875);
DISPLAY INVISIBLE (-2050 1875);
FORCEPROP 2 LAST CDS_LIB mstr_discrete
J 0
(-2000 1775);
PAINT ORANGE (-2000 1775);
DISPLAY INVISIBLE (-2000 1775);
FORCEADD RES..1
(-2000 1525);
FORCEPROP 1 LAST VALUE 0.0
J 2
(-2100 1425);
DISPLAY 0.617021 (-2100 1425);
PAINT SKYBLUE (-2100 1425);
FORCEPROP 1 LASTPIN (-2100 1525) $PN 1
J 0
(-2088 1537);
DISPLAY 0.617021 (-2088 1537);
PAINT WHITE (-2088 1537);
FORCEPROP 1 LAST WATTAGE 1/16W
J 2
(-2025 1375);
DISPLAY 0.617021 (-2025 1375);
PAINT SKYBLUE (-2025 1375);
FORCEPROP 1 LAST TOLERANCE 5%
J 0
(-2050 1425);
DISPLAY 0.617021 (-2050 1425);
PAINT SKYBLUE (-2050 1425);
FORCEPROP 1 LAST PART_NUMBER G21497-005
J 0
(-2150 1475);
DISPLAY 0.617021 (-2150 1475);
PAINT BLUE (-2150 1475);
FORCEPROP 1 LAST LOCATION R1C25
J 0
(-2050 1575);
DISPLAY 0.617021 (-2050 1575);
PAINT AQUA (-2050 1575);
FORCEPROP 1 LAST PACK_TYPE 0402
J 0
(-1925 1425);
DISPLAY 0.617021 (-1925 1425);
PAINT SKYBLUE (-1925 1425);
FORCEPROP 1 LAST MATERIAL CHIP
J 0
(-2000 1375);
DISPLAY 0.617021 (-2000 1375);
PAINT SKYBLUE (-2000 1375);
FORCEPROP 1 LASTPIN (-1900 1525) $PN 2
J 0
(-1938 1537);
DISPLAY 0.617021 (-1938 1537);
PAINT WHITE (-1938 1537);
FORCEPROP 2 LAST ROOM PVCCIN_CPU1_VR
J 0
(-2050 1625);
DISPLAY 1.361702 (-2050 1625);
PAINT WHITE (-2050 1625);
DISPLAY INVISIBLE (-2050 1625);
FORCEPROP 1 LAST PATH I28
J 0
(-2050 1675);
DISPLAY 0.978723 (-2050 1675);
PAINT WHITE (-2050 1675);
DISPLAY INVISIBLE (-2050 1675);
FORCEPROP 2 LAST CDS_LOCATION R1C25
J 0
(-2050 1575);
DISPLAY 0.617021 (-2050 1575);
PAINT AQUA (-2050 1575);
DISPLAY INVISIBLE (-2050 1575);
FORCEPROP 2 LAST SEC 1
J 0
(-2050 1725);
DISPLAY 0.680851 (-2050 1725);
PAINT MONO (-2050 1725);
DISPLAY INVISIBLE (-2050 1725);
FORCEPROP 2 LAST SEC_TYPE 0402
J 0
(-2050 1725);
DISPLAY 1.021277 (-2050 1725);
PAINT ORANGE (-2050 1725);
DISPLAY INVISIBLE (-2050 1725);
FORCEPROP 2 LAST CDS_LIB mstr_discrete
J 0
(-2000 1525);
PAINT ORANGE (-2000 1525);
DISPLAY INVISIBLE (-2000 1525);
FORCEADD CAP_A..1
(-1575 1000);
FORCEPROP 1 LAST MATERIAL X6S
J 0
(-1525 900);
DISPLAY 0.617021 (-1525 900);
PAINT SKYBLUE (-1525 900);
FORCEPROP 1 LAST PACK_TYPE 0402V
J 0
(-1525 800);
DISPLAY 0.617021 (-1525 800);
PAINT SKYBLUE (-1525 800);
FORCEPROP 1 LAST TOLERANCE 10%
J 0
(-1525 950);
DISPLAY 0.617021 (-1525 950);
PAINT SKYBLUE (-1525 950);
FORCEPROP 1 LAST PART_NUMBER D97712-004
J 0
(-1525 850);
DISPLAY 0.617021 (-1525 850);
PAINT BLUE (-1525 850);
FORCEPROP 1 LAST VOLTAGE 6.3V
J 0
(-1525 1000);
DISPLAY 0.617021 (-1525 1000);
PAINT SKYBLUE (-1525 1000);
FORCEPROP 1 LAST LOCATION C1C13
J 0
(-1525 1100);
DISPLAY 0.617021 (-1525 1100);
PAINT AQUA (-1525 1100);
FORCEPROP 1 LAST VALUE 1.0UF
J 0
(-1525 1050);
DISPLAY 0.617021 (-1525 1050);
PAINT SKYBLUE (-1525 1050);
FORCEPROP 1 LASTPIN (-1575 900) $PN 2
J 0
(-1565 880);
DISPLAY 0.787234 (-1565 880);
PAINT ORANGE (-1565 880);
DISPLAY INVISIBLE (-1565 880);
FORCEPROP 2 LAST CDS_LIB dev_discrete
J 0
(-1575 1000);
PAINT ORANGE (-1575 1000);
DISPLAY INVISIBLE (-1575 1000);
FORCEPROP 1 LASTPIN (-1575 1100) $PN 1
J 0
(-1565 1080);
DISPLAY 0.787234 (-1565 1080);
PAINT ORANGE (-1565 1080);
DISPLAY INVISIBLE (-1565 1080);
FORCEPROP 2 LAST CDS_LOCATION C1C13
J 0
(-1525 1100);
DISPLAY 0.617021 (-1525 1100);
PAINT AQUA (-1525 1100);
DISPLAY INVISIBLE (-1525 1100);
FORCEPROP 2 LAST CDS_SEC 1
J 0
(-1525 1200);
DISPLAY 1.021277 (-1525 1200);
PAINT ORANGE (-1525 1200);
DISPLAY INVISIBLE (-1525 1200);
FORCEPROP 2 LAST $SEC 1
J 0
(-1525 1200);
DISPLAY 0.680851 (-1525 1200);
PAINT MONO (-1525 1200);
DISPLAY INVISIBLE (-1525 1200);
FORCEPROP 1 LAST PATH I29
J 0
(-1525 1150);
DISPLAY 0.978723 (-1525 1150);
PAINT WHITE (-1525 1150);
DISPLAY INVISIBLE (-1525 1150);
FORCEPROP 2 LAST ROOM PVCCIN_CPU1_VR
J 0
(-1525 1150);
DISPLAY 1.361702 (-1525 1150);
PAINT WHITE (-1525 1150);
DISPLAY INVISIBLE (-1525 1150);
FORCEADD GND..1
(-1575 675);
FORCEPROP 3 LASTPIN (-1575 725) SIG_NAME GND\g
J 0
(-1565 735);
DISPLAY 0.659574 (-1565 735);
PAINT MONO (-1565 735);
DISPLAY INVISIBLE (-1565 735);
FORCEPROP 2 LAST ROOM PVCCIN_CPU1_VR
J 0
(-2150 750);
DISPLAY 1.361702 (-2150 750);
PAINT WHITE (-2150 750);
DISPLAY INVISIBLE (-2150 750);
FORCEPROP 1 LAST VOLTAGE 0
J 0
(-1575 675);
PAINT SKYBLUE (-1575 675);
DISPLAY INVISIBLE (-1575 675);
FORCEPROP 2 LAST CDS_LIB mstr_symbols
J 0
(-1575 675);
PAINT ORANGE (-1575 675);
DISPLAY INVISIBLE (-1575 675);
FORCEPROP 1 LAST PATH I30
J 0
(-1500 675);
DISPLAY 0.872340 (-1500 675);
PAINT AQUA (-1500 675);
DISPLAY INVISIBLE (-1500 675);
FORCEPROP 1 LAST SIZE 1B
J 0
(-1500 625);
DISPLAY 1.170213 (-1500 625);
PAINT AQUA (-1500 625);
DISPLAY INVISIBLE (-1500 625);
FORCEPROP 1 LAST BODY_TYPE PLUMBING
J 0
(-1620 632);
DISPLAY 0.340426 (-1620 632);
PAINT GREEN (-1620 632);
DISPLAY INVISIBLE (-1620 632);
FORCEPROP 1 LAST HDL_POWER GND
J 0
(-1575 825);
DISPLAY 1.170213 (-1575 825);
PAINT GREEN (-1575 825);
DISPLAY INVISIBLE (-1575 825);
FORCEADD CAP_A..1
(-1975 1000);
FORCEPROP 1 LASTPIN (-1975 900) $PN 2
J 0
(-1965 880);
DISPLAY 0.617021 (-1965 880);
PAINT WHITE (-1965 880);
FORCEPROP 1 LAST MATERIAL X7R
J 0
(-1925 900);
DISPLAY 0.617021 (-1925 900);
PAINT SKYBLUE (-1925 900);
FORCEPROP 1 LAST TOLERANCE 10%
J 0
(-1925 950);
DISPLAY 0.617021 (-1925 950);
PAINT SKYBLUE (-1925 950);
FORCEPROP 1 LAST PACK_TYPE 0402V
J 0
(-1925 800);
DISPLAY 0.617021 (-1925 800);
PAINT SKYBLUE (-1925 800);
FORCEPROP 1 LAST PART_NUMBER A36096-030
J 0
(-1925 850);
DISPLAY 0.617021 (-1925 850);
PAINT BLUE (-1925 850);
FORCEPROP 1 LAST VOLTAGE 16V
J 0
(-1925 1000);
DISPLAY 0.617021 (-1925 1000);
PAINT SKYBLUE (-1925 1000);
FORCEPROP 1 LASTPIN (-1975 1100) $PN 1
J 0
(-1965 1080);
DISPLAY 0.617021 (-1965 1080);
PAINT WHITE (-1965 1080);
FORCEPROP 1 LAST LOCATION C1C14
J 0
(-1925 1100);
DISPLAY 0.617021 (-1925 1100);
PAINT AQUA (-1925 1100);
FORCEPROP 1 LAST VALUE 0.1UF
J 0
(-1925 1050);
DISPLAY 0.617021 (-1925 1050);
PAINT SKYBLUE (-1925 1050);
FORCEPROP 2 LAST CDS_LIB dev_discrete
J 0
(-1975 1000);
PAINT ORANGE (-1975 1000);
DISPLAY INVISIBLE (-1975 1000);
FORCEPROP 2 LAST SEC 1
J 0
(-1925 1200);
DISPLAY 0.680851 (-1925 1200);
PAINT MONO (-1925 1200);
DISPLAY INVISIBLE (-1925 1200);
FORCEPROP 2 LAST SEC_TYPE 0402V
J 0
(-1925 1200);
DISPLAY 1.021277 (-1925 1200);
PAINT ORANGE (-1925 1200);
DISPLAY INVISIBLE (-1925 1200);
FORCEPROP 2 LAST CDS_SEC 1
J 0
(-1925 1150);
PAINT ORANGE (-1925 1150);
DISPLAY INVISIBLE (-1925 1150);
FORCEPROP 2 LAST CDS_LOCATION C1C14
J 0
(-1925 1100);
DISPLAY 0.617021 (-1925 1100);
PAINT AQUA (-1925 1100);
DISPLAY INVISIBLE (-1925 1100);
FORCEPROP 2 LAST ROOM PVCCIN_CPU1_VR
J 0
(-1925 1150);
DISPLAY 1.361702 (-1925 1150);
PAINT WHITE (-1925 1150);
DISPLAY INVISIBLE (-1925 1150);
FORCEPROP 1 LAST PATH I31
J 0
(-1925 1150);
DISPLAY 0.978723 (-1925 1150);
PAINT WHITE (-1925 1150);
DISPLAY INVISIBLE (-1925 1150);
FORCEADD GND..1
(-1975 800);
FORCEPROP 3 LASTPIN (-1975 850) SIG_NAME GND\g
J 0
(-1965 860);
DISPLAY 0.659574 (-1965 860);
PAINT MONO (-1965 860);
DISPLAY INVISIBLE (-1965 860);
FORCEPROP 2 LAST ROOM PVCCIN_CPU1_VR
J 0
(-2550 875);
DISPLAY 1.361702 (-2550 875);
PAINT WHITE (-2550 875);
DISPLAY INVISIBLE (-2550 875);
FORCEPROP 1 LAST SIZE 1B
J 0
(-1900 750);
DISPLAY 1.170213 (-1900 750);
PAINT AQUA (-1900 750);
DISPLAY INVISIBLE (-1900 750);
FORCEPROP 1 LAST VOLTAGE 0
J 0
(-1975 800);
PAINT SKYBLUE (-1975 800);
DISPLAY INVISIBLE (-1975 800);
FORCEPROP 2 LAST CDS_LIB mstr_symbols
J 0
(-1975 800);
PAINT ORANGE (-1975 800);
DISPLAY INVISIBLE (-1975 800);
FORCEPROP 1 LAST PATH I32
J 0
(-1900 800);
DISPLAY 0.872340 (-1900 800);
PAINT AQUA (-1900 800);
DISPLAY INVISIBLE (-1900 800);
FORCEPROP 1 LAST BODY_TYPE PLUMBING
J 0
(-2020 757);
DISPLAY 0.340426 (-2020 757);
PAINT GREEN (-2020 757);
DISPLAY INVISIBLE (-2020 757);
FORCEPROP 1 LAST HDL_POWER GND
J 0
(-1975 950);
DISPLAY 1.170213 (-1975 950);
PAINT GREEN (-1975 950);
DISPLAY INVISIBLE (-1975 950);
FORCEADD RES..2
(-2375 4125);
FORCEPROP 1 LASTPIN (-2375 4025) $PN 2
J 0
(-2370 4035);
DISPLAY 0.617021 (-2370 4035);
PAINT WHITE (-2370 4035);
FORCEPROP 1 LAST PACK_TYPE 0402
J 0
(-2335 3950);
DISPLAY 0.617021 (-2335 3950);
PAINT SKYBLUE (-2335 3950);
FORCEPROP 1 LAST PART_NUMBER G21796-311
J 0
(-2335 4000);
DISPLAY 0.617021 (-2335 4000);
PAINT BLUE (-2335 4000);
FORCEPROP 1 LAST MATERIAL EMPTY
J 0
(-2535 4225);
DISPLAY 0.617021 (-2535 4225);
PAINT RED (-2535 4225);
FORCEPROP 1 LASTPIN (-2375 4225) $PN 1
J 0
(-2370 4187);
DISPLAY 0.617021 (-2370 4187);
PAINT WHITE (-2370 4187);
FORCEPROP 1 LAST WATTAGE 1/16W
J 0
(-2335 4100);
DISPLAY 0.617021 (-2335 4100);
PAINT SKYBLUE (-2335 4100);
FORCEPROP 1 LAST TOLERANCE 1.0%
J 0
(-2330 4150);
DISPLAY 0.617021 (-2330 4150);
PAINT SKYBLUE (-2330 4150);
FORCEPROP 1 LAST VALUE 2.26K
J 0
(-2330 4200);
DISPLAY 0.617021 (-2330 4200);
PAINT SKYBLUE (-2330 4200);
FORCEPROP 1 LAST LOCATION R1D53
J 0
(-2330 4250);
DISPLAY 0.617021 (-2330 4250);
PAINT AQUA (-2330 4250);
FORCEPROP 2 LAST ROOM PVCCIN_CPU1_VR
J 0
(-2525 4275);
DISPLAY 1.361702 (-2525 4275);
PAINT WHITE (-2525 4275);
DISPLAY INVISIBLE (-2525 4275);
FORCEPROP 2 LAST CDS_LIB mstr_discrete
J 0
(-2375 4125);
PAINT ORANGE (-2375 4125);
DISPLAY INVISIBLE (-2375 4125);
FORCEPROP 1 LAST PATH I33
J 0
(-2325 4300);
DISPLAY 0.978723 (-2325 4300);
PAINT WHITE (-2325 4300);
DISPLAY INVISIBLE (-2325 4300);
FORCEPROP 2 LAST SEC 1
J 0
(-2325 4350);
DISPLAY 0.680851 (-2325 4350);
PAINT MONO (-2325 4350);
DISPLAY INVISIBLE (-2325 4350);
FORCEPROP 2 LAST SEC_TYPE 0402
J 0
(-2325 4350);
DISPLAY 1.021277 (-2325 4350);
PAINT ORANGE (-2325 4350);
DISPLAY INVISIBLE (-2325 4350);
FORCEADD RES..2
(-2225 3750);
FORCEPROP 1 LAST PACK_TYPE 0402
J 0
(-2185 3575);
DISPLAY 0.617021 (-2185 3575);
PAINT SKYBLUE (-2185 3575);
FORCEPROP 1 LASTPIN (-2225 3650) $PN 2
J 0
(-2220 3660);
DISPLAY 0.617021 (-2220 3660);
PAINT WHITE (-2220 3660);
FORCEPROP 1 LASTPIN (-2225 3850) $PN 1
J 0
(-2220 3812);
DISPLAY 0.617021 (-2220 3812);
PAINT WHITE (-2220 3812);
FORCEPROP 1 LAST TOLERANCE 1.0%
J 0
(-2180 3775);
DISPLAY 0.617021 (-2180 3775);
PAINT SKYBLUE (-2180 3775);
FORCEPROP 1 LAST WATTAGE 1/16W
J 0
(-2185 3725);
DISPLAY 0.617021 (-2185 3725);
PAINT SKYBLUE (-2185 3725);
FORCEPROP 1 LAST VALUE 2.26K
J 0
(-2180 3825);
DISPLAY 0.617021 (-2180 3825);
PAINT SKYBLUE (-2180 3825);
FORCEPROP 1 LAST PART_NUMBER G21796-311
J 0
(-2185 3625);
DISPLAY 0.617021 (-2185 3625);
PAINT BLUE (-2185 3625);
FORCEPROP 1 LAST LOCATION R1C18
J 0
(-2180 3875);
DISPLAY 0.617021 (-2180 3875);
PAINT AQUA (-2180 3875);
FORCEPROP 1 LAST MATERIAL EMPTY
J 0
(-2185 3675);
DISPLAY 0.617021 (-2185 3675);
PAINT RED (-2185 3675);
FORCEPROP 2 LAST CDS_LIB mstr_discrete
J 0
(-2225 3750);
PAINT ORANGE (-2225 3750);
DISPLAY INVISIBLE (-2225 3750);
FORCEPROP 2 LAST ROOM PVCCIN_CPU1_VR
J 0
(-2175 3725);
DISPLAY 1.361702 (-2175 3725);
PAINT WHITE (-2175 3725);
DISPLAY INVISIBLE (-2175 3725);
FORCEPROP 1 LAST PATH I34
J 0
(-2175 3925);
DISPLAY 0.978723 (-2175 3925);
PAINT WHITE (-2175 3925);
DISPLAY INVISIBLE (-2175 3925);
FORCEPROP 2 LAST CDS_LOCATION R1C18
J 0
(-2180 3875);
DISPLAY 0.617021 (-2180 3875);
PAINT AQUA (-2180 3875);
DISPLAY INVISIBLE (-2180 3875);
FORCEPROP 2 LAST SEC 1
J 0
(-2175 3975);
DISPLAY 0.680851 (-2175 3975);
PAINT MONO (-2175 3975);
DISPLAY INVISIBLE (-2175 3975);
FORCEPROP 2 LAST SEC_TYPE 0402
J 0
(-2175 3975);
DISPLAY 1.021277 (-2175 3975);
PAINT ORANGE (-2175 3975);
DISPLAY INVISIBLE (-2175 3975);
FORCEADD RES..2
(-2725 3925);
FORCEPROP 1 LAST PACK_TYPE 0402
J 0
(-2685 3750);
DISPLAY 0.617021 (-2685 3750);
PAINT SKYBLUE (-2685 3750);
FORCEPROP 1 LASTPIN (-2725 3825) $PN 2
J 0
(-2720 3835);
DISPLAY 0.617021 (-2720 3835);
PAINT WHITE (-2720 3835);
FORCEPROP 1 LAST TOLERANCE 1%
J 0
(-2680 3950);
DISPLAY 0.617021 (-2680 3950);
PAINT SKYBLUE (-2680 3950);
FORCEPROP 1 LAST MATERIAL CHIP
J 0
(-2685 3850);
DISPLAY 0.617021 (-2685 3850);
PAINT SKYBLUE (-2685 3850);
FORCEPROP 1 LASTPIN (-2725 4025) $PN 1
J 0
(-2720 3987);
DISPLAY 0.617021 (-2720 3987);
PAINT WHITE (-2720 3987);
FORCEPROP 1 LAST WATTAGE 1/16W
J 0
(-2685 3900);
DISPLAY 0.617021 (-2685 3900);
PAINT SKYBLUE (-2685 3900);
FORCEPROP 1 LAST VALUE 1.00K
J 0
(-2680 4000);
DISPLAY 0.617021 (-2680 4000);
PAINT SKYBLUE (-2680 4000);
FORCEPROP 1 LAST PART_NUMBER G21796-026
J 0
(-2685 3800);
DISPLAY 0.617021 (-2685 3800);
PAINT BLUE (-2685 3800);
FORCEPROP 1 LAST LOCATION R1C28
J 0
(-2680 4050);
DISPLAY 0.617021 (-2680 4050);
PAINT AQUA (-2680 4050);
FORCEPROP 2 LAST CDS_LIB mstr_discrete
J 2
(-2725 3925);
PAINT ORANGE (-2725 3925);
DISPLAY INVISIBLE (-2725 3925);
FORCEPROP 2 LAST CDS_LOCATION R1C28
J 0
(-2680 4050);
DISPLAY 0.617021 (-2680 4050);
PAINT AQUA (-2680 4050);
DISPLAY INVISIBLE (-2680 4050);
FORCEPROP 2 LAST ROOM PVCCIN_CPU1_VR
J 0
(-2675 4100);
DISPLAY 1.361702 (-2675 4100);
PAINT WHITE (-2675 4100);
DISPLAY INVISIBLE (-2675 4100);
FORCEPROP 1 LAST PATH I35
J 0
(-2675 4100);
DISPLAY 0.978723 (-2675 4100);
PAINT WHITE (-2675 4100);
DISPLAY INVISIBLE (-2675 4100);
FORCEPROP 2 LAST SEC 1
J 0
(-2675 4150);
DISPLAY 0.680851 (-2675 4150);
PAINT MONO (-2675 4150);
DISPLAY INVISIBLE (-2675 4150);
FORCEPROP 2 LAST SEC_TYPE 0402
J 0
(-2675 4150);
DISPLAY 1.021277 (-2675 4150);
PAINT ORANGE (-2675 4150);
DISPLAY INVISIBLE (-2675 4150);
FORCEADD RES..2
R 2
(-2875 3925);
FORCEPROP 1 LAST PART_NUMBER G21796-026
J 2
(-2915 3800);
DISPLAY 0.617021 (-2915 3800);
PAINT BLUE (-2915 3800);
FORCEPROP 1 LAST PACK_TYPE 0402
J 2
(-2915 3750);
DISPLAY 0.617021 (-2915 3750);
PAINT SKYBLUE (-2915 3750);
FORCEPROP 1 LASTPIN (-2875 3825) $PN 2
J 2
(-2880 3835);
DISPLAY 0.617021 (-2880 3835);
PAINT WHITE (-2880 3835);
FORCEPROP 1 LAST WATTAGE 1/16W
J 2
(-2915 3900);
DISPLAY 0.617021 (-2915 3900);
PAINT SKYBLUE (-2915 3900);
FORCEPROP 1 LAST LOCATION R1D8
J 2
(-2920 4050);
DISPLAY 0.617021 (-2920 4050);
PAINT AQUA (-2920 4050);
FORCEPROP 1 LAST VALUE 1.00K
J 2
(-2920 4000);
DISPLAY 0.617021 (-2920 4000);
PAINT SKYBLUE (-2920 4000);
FORCEPROP 1 LAST TOLERANCE 1%
J 2
(-2920 3950);
DISPLAY 0.617021 (-2920 3950);
PAINT SKYBLUE (-2920 3950);
FORCEPROP 1 LAST MATERIAL CHIP
J 2
(-2915 3850);
DISPLAY 0.617021 (-2915 3850);
PAINT SKYBLUE (-2915 3850);
FORCEPROP 1 LASTPIN (-2875 4025) $PN 1
J 2
(-2880 3987);
DISPLAY 0.617021 (-2880 3987);
PAINT WHITE (-2880 3987);
FORCEPROP 2 LAST CDS_LOCATION R1D8
J 2
(-2920 4050);
DISPLAY 0.617021 (-2920 4050);
PAINT AQUA (-2920 4050);
DISPLAY INVISIBLE (-2920 4050);
FORCEPROP 2 LAST CDS_LIB mstr_discrete
J 2
(-2875 3925);
PAINT ORANGE (-2875 3925);
DISPLAY INVISIBLE (-2875 3925);
FORCEPROP 2 LAST ROOM PVCCIN_CPU1_VR
J 0
(-2900 4100);
DISPLAY 1.361702 (-2900 4100);
PAINT WHITE (-2900 4100);
DISPLAY INVISIBLE (-2900 4100);
FORCEPROP 1 LAST PATH I36
J 2
(-2925 4100);
DISPLAY 0.978723 (-2925 4100);
PAINT WHITE (-2925 4100);
DISPLAY INVISIBLE (-2925 4100);
FORCEPROP 2 LAST SEC 1
J 0
(-2925 4150);
DISPLAY 0.680851 (-2925 4150);
PAINT MONO (-2925 4150);
DISPLAY INVISIBLE (-2925 4150);
FORCEPROP 2 LAST SEC_TYPE 0402
J 0
(-2925 4150);
DISPLAY 1.021277 (-2925 4150);
PAINT ORANGE (-2925 4150);
DISPLAY INVISIBLE (-2925 4150);
FORCEADD RES..1
(-2125 2925);
FORCEPROP 1 LAST PART_NUMBER G21497-005
J 0
(-3200 2875);
DISPLAY 0.617021 (-3200 2875);
PAINT BLUE (-3200 2875);
FORCEPROP 1 LAST WATTAGE 1/16W
J 2
(-2575 2975);
DISPLAY 0.617021 (-2575 2975);
PAINT SKYBLUE (-2575 2975);
FORCEPROP 1 LAST VALUE 0.0
J 2
(-2300 2875);
DISPLAY 0.617021 (-2300 2875);
PAINT SKYBLUE (-2300 2875);
FORCEPROP 1 LAST TOLERANCE 5%
J 0
(-2250 2875);
DISPLAY 0.617021 (-2250 2875);
PAINT SKYBLUE (-2250 2875);
FORCEPROP 1 LASTPIN (-2225 2925) $PN 1
J 0
(-2213 2937);
DISPLAY 0.617021 (-2213 2937);
PAINT WHITE (-2213 2937);
FORCEPROP 1 LAST LOCATION R1D3
J 0
(-2175 2975);
DISPLAY 0.617021 (-2175 2975);
PAINT AQUA (-2175 2975);
FORCEPROP 1 LASTPIN (-2025 2925) $PN 2
J 0
(-2063 2937);
DISPLAY 0.617021 (-2063 2937);
PAINT WHITE (-2063 2937);
FORCEPROP 1 LAST PACK_TYPE 0402
J 0
(-2025 2875);
DISPLAY 0.617021 (-2025 2875);
PAINT SKYBLUE (-2025 2875);
FORCEPROP 1 LAST MATERIAL CHIP
J 0
(-1900 2875);
DISPLAY 0.617021 (-1900 2875);
PAINT SKYBLUE (-1900 2875);
FORCEPROP 2 LAST CDS_LIB mstr_discrete
J 0
(-2125 2925);
PAINT ORANGE (-2125 2925);
DISPLAY INVISIBLE (-2125 2925);
FORCEPROP 2 LAST CDS_LOCATION R1D3
J 0
(-2175 2975);
DISPLAY 0.617021 (-2175 2975);
PAINT AQUA (-2175 2975);
DISPLAY INVISIBLE (-2175 2975);
FORCEPROP 2 LAST ROOM PVCCIN_CPU1_VR
J 0
(-2175 3025);
DISPLAY 1.361702 (-2175 3025);
PAINT WHITE (-2175 3025);
DISPLAY INVISIBLE (-2175 3025);
FORCEPROP 2 LAST SEC_TYPE 0402
J 0
(-2175 3125);
DISPLAY 1.021277 (-2175 3125);
PAINT ORANGE (-2175 3125);
DISPLAY INVISIBLE (-2175 3125);
FORCEPROP 2 LAST SEC 1
J 0
(-2175 3125);
DISPLAY 0.680851 (-2175 3125);
PAINT MONO (-2175 3125);
DISPLAY INVISIBLE (-2175 3125);
FORCEPROP 1 LAST PATH I37
J 0
(-2175 3075);
DISPLAY 0.978723 (-2175 3075);
PAINT WHITE (-2175 3075);
DISPLAY INVISIBLE (-2175 3075);
FORCEADD RES..1
(-2500 2775);
FORCEPROP 1 LAST VALUE 0.0
J 2
(-2625 2625);
DISPLAY 0.617021 (-2625 2625);
PAINT SKYBLUE (-2625 2625);
FORCEPROP 1 LASTPIN (-2600 2775) $PN 1
J 0
(-2588 2787);
DISPLAY 0.617021 (-2588 2787);
PAINT WHITE (-2588 2787);
FORCEPROP 1 LAST WATTAGE 1/16W
J 2
(-2525 2575);
DISPLAY 0.617021 (-2525 2575);
PAINT SKYBLUE (-2525 2575);
FORCEPROP 1 LAST TOLERANCE 5%
J 0
(-2575 2625);
DISPLAY 0.617021 (-2575 2625);
PAINT SKYBLUE (-2575 2625);
FORCEPROP 1 LAST PART_NUMBER G21497-005
J 0
(-2650 2675);
DISPLAY 0.617021 (-2650 2675);
PAINT BLUE (-2650 2675);
FORCEPROP 1 LASTPIN (-2400 2775) $PN 2
J 0
(-2438 2787);
DISPLAY 0.617021 (-2438 2787);
PAINT WHITE (-2438 2787);
FORCEPROP 1 LAST MATERIAL CHIP
J 0
(-2475 2575);
DISPLAY 0.617021 (-2475 2575);
PAINT SKYBLUE (-2475 2575);
FORCEPROP 1 LAST PACK_TYPE 0402
J 0
(-2475 2625);
DISPLAY 0.617021 (-2475 2625);
PAINT SKYBLUE (-2475 2625);
FORCEPROP 1 LAST LOCATION R1D2
J 0
(-2550 2825);
DISPLAY 0.617021 (-2550 2825);
PAINT AQUA (-2550 2825);
FORCEPROP 2 LAST CDS_LIB mstr_discrete
J 0
(-2500 2775);
PAINT ORANGE (-2500 2775);
DISPLAY INVISIBLE (-2500 2775);
FORCEPROP 2 LAST SEC_TYPE 0402
J 0
(-2550 2975);
DISPLAY 1.021277 (-2550 2975);
PAINT ORANGE (-2550 2975);
DISPLAY INVISIBLE (-2550 2975);
FORCEPROP 2 LAST SEC 1
J 0
(-2550 2975);
DISPLAY 0.680851 (-2550 2975);
PAINT MONO (-2550 2975);
DISPLAY INVISIBLE (-2550 2975);
FORCEPROP 2 LAST CDS_LOCATION R1D2
J 0
(-2550 2825);
DISPLAY 0.617021 (-2550 2825);
PAINT AQUA (-2550 2825);
DISPLAY INVISIBLE (-2550 2825);
FORCEPROP 1 LAST PATH I38
J 0
(-2550 2925);
DISPLAY 0.978723 (-2550 2925);
PAINT WHITE (-2550 2925);
DISPLAY INVISIBLE (-2550 2925);
FORCEPROP 2 LAST ROOM PVCCIN_CPU1_VR
J 0
(-2550 2875);
DISPLAY 1.361702 (-2550 2875);
PAINT WHITE (-2550 2875);
DISPLAY INVISIBLE (-2550 2875);
FORCEADD RES..2
(-1375 3750);
FORCEPROP 1 LAST PACK_TYPE 0402
J 0
(-1335 3575);
DISPLAY 0.617021 (-1335 3575);
PAINT SKYBLUE (-1335 3575);
FORCEPROP 1 LASTPIN (-1375 3650) $PN 2
J 0
(-1370 3660);
DISPLAY 0.617021 (-1370 3660);
PAINT WHITE (-1370 3660);
FORCEPROP 1 LASTPIN (-1375 3850) $PN 1
J 0
(-1370 3812);
DISPLAY 0.617021 (-1370 3812);
PAINT WHITE (-1370 3812);
FORCEPROP 1 LAST WATTAGE 1/16W
J 0
(-1335 3725);
DISPLAY 0.617021 (-1335 3725);
PAINT SKYBLUE (-1335 3725);
FORCEPROP 1 LAST LOCATION R9P1
J 0
(-1330 3875);
DISPLAY 0.617021 (-1330 3875);
PAINT AQUA (-1330 3875);
FORCEPROP 1 LAST PART_NUMBER G21796-017
J 0
(-1335 3625);
DISPLAY 0.617021 (-1335 3625);
PAINT BLUE (-1335 3625);
FORCEPROP 1 LAST MATERIAL CHIP
J 0
(-1335 3675);
DISPLAY 0.617021 (-1335 3675);
PAINT SKYBLUE (-1335 3675);
FORCEPROP 1 LAST TOLERANCE 1%
J 0
(-1330 3775);
DISPLAY 0.617021 (-1330 3775);
PAINT SKYBLUE (-1330 3775);
FORCEPROP 1 LAST VALUE 100.0
J 0
(-1330 3825);
DISPLAY 0.617021 (-1330 3825);
PAINT SKYBLUE (-1330 3825);
FORCEPROP 2 LAST CDS_LIB mstr_discrete
J 0
(-1375 3750);
PAINT ORANGE (-1375 3750);
DISPLAY INVISIBLE (-1375 3750);
FORCEPROP 2 LAST ROOM PVCCIN_CPU1_VR
J 0
(-1325 3925);
DISPLAY 1.361702 (-1325 3925);
PAINT WHITE (-1325 3925);
DISPLAY INVISIBLE (-1325 3925);
FORCEPROP 1 LAST PATH I4
J 0
(-1325 3925);
DISPLAY 0.978723 (-1325 3925);
PAINT WHITE (-1325 3925);
DISPLAY INVISIBLE (-1325 3925);
FORCEPROP 2 LAST CDS_LOCATION R9P1
J 0
(-1330 3875);
DISPLAY 0.617021 (-1330 3875);
PAINT AQUA (-1330 3875);
DISPLAY INVISIBLE (-1330 3875);
FORCEPROP 2 LAST SEC 1
J 0
(-1325 3975);
DISPLAY 0.680851 (-1325 3975);
PAINT MONO (-1325 3975);
DISPLAY INVISIBLE (-1325 3975);
FORCEPROP 2 LAST SEC_TYPE 0402
J 0
(-1325 3975);
DISPLAY 1.021277 (-1325 3975);
PAINT ORANGE (-1325 3975);
DISPLAY INVISIBLE (-1325 3975);
FORCEADD GND..1
(-3650 3725);
FORCEPROP 3 LASTPIN (-3650 3775) SIG_NAME GND\g
J 0
(-3640 3785);
DISPLAY 0.659574 (-3640 3785);
PAINT MONO (-3640 3785);
DISPLAY INVISIBLE (-3640 3785);
FORCEPROP 2 LAST ROOM PVCCIN_CPU1_VR
J 0
(-4225 3800);
DISPLAY 1.361702 (-4225 3800);
PAINT WHITE (-4225 3800);
DISPLAY INVISIBLE (-4225 3800);
FORCEPROP 2 LAST CDS_LIB mstr_symbols
J 0
(-3650 3725);
PAINT ORANGE (-3650 3725);
DISPLAY INVISIBLE (-3650 3725);
FORCEPROP 1 LAST VOLTAGE 0
J 0
(-3650 3725);
PAINT SKYBLUE (-3650 3725);
DISPLAY INVISIBLE (-3650 3725);
FORCEPROP 1 LAST PATH I40
J 0
(-3575 3725);
DISPLAY 0.872340 (-3575 3725);
PAINT AQUA (-3575 3725);
DISPLAY INVISIBLE (-3575 3725);
FORCEPROP 1 LAST SIZE 1B
J 0
(-3575 3675);
DISPLAY 1.170213 (-3575 3675);
PAINT AQUA (-3575 3675);
DISPLAY INVISIBLE (-3575 3675);
FORCEPROP 1 LAST BODY_TYPE PLUMBING
J 0
(-3695 3682);
DISPLAY 0.340426 (-3695 3682);
PAINT GREEN (-3695 3682);
DISPLAY INVISIBLE (-3695 3682);
FORCEPROP 1 LAST HDL_POWER GND
J 0
(-3650 3875);
DISPLAY 1.170213 (-3650 3875);
PAINT GREEN (-3650 3875);
DISPLAY INVISIBLE (-3650 3875);
FORCEADD CAP_A..1
(-3650 3925);
FORCEPROP 1 LAST MATERIAL X6S
J 0
(-3600 3825);
DISPLAY 0.617021 (-3600 3825);
PAINT SKYBLUE (-3600 3825);
FORCEPROP 1 LAST VOLTAGE 6.3V
J 0
(-3600 3925);
DISPLAY 0.617021 (-3600 3925);
PAINT SKYBLUE (-3600 3925);
FORCEPROP 1 LAST PACK_TYPE 0402V
J 0
(-3600 3725);
DISPLAY 0.617021 (-3600 3725);
PAINT SKYBLUE (-3600 3725);
FORCEPROP 1 LAST TOLERANCE 10%
J 0
(-3600 3875);
DISPLAY 0.617021 (-3600 3875);
PAINT SKYBLUE (-3600 3875);
FORCEPROP 1 LAST VALUE 1.0UF
J 0
(-3600 3975);
DISPLAY 0.617021 (-3600 3975);
PAINT SKYBLUE (-3600 3975);
FORCEPROP 1 LAST PART_NUMBER D97712-004
J 0
(-3600 3775);
DISPLAY 0.617021 (-3600 3775);
PAINT BLUE (-3600 3775);
FORCEPROP 1 LAST LOCATION C1C7
J 0
(-3600 4025);
DISPLAY 0.617021 (-3600 4025);
PAINT AQUA (-3600 4025);
FORCEPROP 1 LASTPIN (-3650 3825) $PN 2
J 0
(-3640 3805);
DISPLAY 0.787234 (-3640 3805);
PAINT ORANGE (-3640 3805);
DISPLAY INVISIBLE (-3640 3805);
FORCEPROP 2 LAST CDS_LIB dev_discrete
J 0
(-3650 3925);
PAINT ORANGE (-3650 3925);
DISPLAY INVISIBLE (-3650 3925);
FORCEPROP 2 LAST CDS_LOCATION C1C7
J 0
(-3600 4025);
DISPLAY 0.617021 (-3600 4025);
PAINT AQUA (-3600 4025);
DISPLAY INVISIBLE (-3600 4025);
FORCEPROP 1 LASTPIN (-3650 4025) $PN 1
J 0
(-3640 4005);
DISPLAY 0.787234 (-3640 4005);
PAINT ORANGE (-3640 4005);
DISPLAY INVISIBLE (-3640 4005);
FORCEPROP 2 LAST ROOM PVCCIN_CPU1_VR
J 0
(-3600 4075);
DISPLAY 1.361702 (-3600 4075);
PAINT WHITE (-3600 4075);
DISPLAY INVISIBLE (-3600 4075);
FORCEPROP 1 LAST PATH I41
J 0
(-3600 4075);
DISPLAY 0.978723 (-3600 4075);
PAINT WHITE (-3600 4075);
DISPLAY INVISIBLE (-3600 4075);
FORCEPROP 2 LAST $SEC 1
J 0
(-3600 4125);
DISPLAY 0.680851 (-3600 4125);
PAINT MONO (-3600 4125);
DISPLAY INVISIBLE (-3600 4125);
FORCEPROP 2 LAST CDS_SEC 1
J 0
(-3600 4125);
DISPLAY 1.021277 (-3600 4125);
PAINT ORANGE (-3600 4125);
DISPLAY INVISIBLE (-3600 4125);
FORCEADD CAP_A..1
(-4050 3925);
FORCEPROP 1 LASTPIN (-4050 3825) $PN 2
J 0
(-4040 3805);
DISPLAY 0.617021 (-4040 3805);
PAINT WHITE (-4040 3805);
FORCEPROP 1 LAST PACK_TYPE 0402V
J 0
(-4000 3725);
DISPLAY 0.617021 (-4000 3725);
PAINT SKYBLUE (-4000 3725);
FORCEPROP 1 LAST MATERIAL X7R
J 0
(-4000 3825);
DISPLAY 0.617021 (-4000 3825);
PAINT SKYBLUE (-4000 3825);
FORCEPROP 1 LASTPIN (-4050 4025) $PN 1
J 0
(-4040 4005);
DISPLAY 0.617021 (-4040 4005);
PAINT WHITE (-4040 4005);
FORCEPROP 1 LAST LOCATION C1C9
J 0
(-4000 4025);
DISPLAY 0.617021 (-4000 4025);
PAINT AQUA (-4000 4025);
FORCEPROP 1 LAST VALUE 0.1UF
J 0
(-4000 3975);
DISPLAY 0.617021 (-4000 3975);
PAINT SKYBLUE (-4000 3975);
FORCEPROP 1 LAST TOLERANCE 10%
J 0
(-4000 3875);
DISPLAY 0.617021 (-4000 3875);
PAINT SKYBLUE (-4000 3875);
FORCEPROP 1 LAST VOLTAGE 16V
J 0
(-4000 3925);
DISPLAY 0.617021 (-4000 3925);
PAINT SKYBLUE (-4000 3925);
FORCEPROP 1 LAST PART_NUMBER A36096-030
J 0
(-4000 3775);
DISPLAY 0.617021 (-4000 3775);
PAINT BLUE (-4000 3775);
FORCEPROP 2 LAST CDS_LIB dev_discrete
J 0
(-4050 3925);
PAINT ORANGE (-4050 3925);
DISPLAY INVISIBLE (-4050 3925);
FORCEPROP 2 LAST CDS_LOCATION C1C9
J 0
(-4000 4025);
DISPLAY 0.617021 (-4000 4025);
PAINT AQUA (-4000 4025);
DISPLAY INVISIBLE (-4000 4025);
FORCEPROP 2 LAST CDS_SEC 1
J 0
(-4000 4075);
PAINT ORANGE (-4000 4075);
DISPLAY INVISIBLE (-4000 4075);
FORCEPROP 2 LAST ROOM PVCCIN_CPU1_VR
J 0
(-4000 4075);
DISPLAY 1.361702 (-4000 4075);
PAINT WHITE (-4000 4075);
DISPLAY INVISIBLE (-4000 4075);
FORCEPROP 1 LAST PATH I42
J 0
(-4000 4075);
DISPLAY 0.978723 (-4000 4075);
PAINT WHITE (-4000 4075);
DISPLAY INVISIBLE (-4000 4075);
FORCEPROP 2 LAST SEC 1
J 0
(-4000 4125);
DISPLAY 0.680851 (-4000 4125);
PAINT MONO (-4000 4125);
DISPLAY INVISIBLE (-4000 4125);
FORCEPROP 2 LAST SEC_TYPE 0402V
J 0
(-4000 4125);
DISPLAY 1.021277 (-4000 4125);
PAINT ORANGE (-4000 4125);
DISPLAY INVISIBLE (-4000 4125);
FORCEADD GND..1
(-4050 3725);
FORCEPROP 3 LASTPIN (-4050 3775) SIG_NAME GND\g
J 0
(-4040 3785);
DISPLAY 0.659574 (-4040 3785);
PAINT MONO (-4040 3785);
DISPLAY INVISIBLE (-4040 3785);
FORCEPROP 2 LAST ROOM PVCCIN_CPU1_VR
J 0
(-4625 3800);
DISPLAY 1.361702 (-4625 3800);
PAINT WHITE (-4625 3800);
DISPLAY INVISIBLE (-4625 3800);
FORCEPROP 1 LAST SIZE 1B
J 0
(-3975 3675);
DISPLAY 1.170213 (-3975 3675);
PAINT AQUA (-3975 3675);
DISPLAY INVISIBLE (-3975 3675);
FORCEPROP 1 LAST PATH I43
J 0
(-3975 3725);
DISPLAY 0.872340 (-3975 3725);
PAINT AQUA (-3975 3725);
DISPLAY INVISIBLE (-3975 3725);
FORCEPROP 2 LAST CDS_LIB mstr_symbols
J 0
(-4050 3725);
PAINT ORANGE (-4050 3725);
DISPLAY INVISIBLE (-4050 3725);
FORCEPROP 1 LAST VOLTAGE 0
J 0
(-4050 3725);
PAINT SKYBLUE (-4050 3725);
DISPLAY INVISIBLE (-4050 3725);
FORCEPROP 1 LAST BODY_TYPE PLUMBING
J 0
(-4095 3682);
DISPLAY 0.340426 (-4095 3682);
PAINT GREEN (-4095 3682);
DISPLAY INVISIBLE (-4095 3682);
FORCEPROP 1 LAST HDL_POWER GND
J 0
(-4050 3875);
DISPLAY 1.170213 (-4050 3875);
PAINT GREEN (-4050 3875);
DISPLAY INVISIBLE (-4050 3875);
FORCEADD GND..1
(-3175 1550);
FORCEPROP 3 LASTPIN (-3175 1600) SIG_NAME GND\g
J 0
(-3165 1610);
DISPLAY 0.659574 (-3165 1610);
PAINT MONO (-3165 1610);
DISPLAY INVISIBLE (-3165 1610);
FORCEPROP 2 LAST ROOM PVCCIN_CPU1_VR
J 0
(-3750 1625);
DISPLAY 1.361702 (-3750 1625);
PAINT WHITE (-3750 1625);
DISPLAY INVISIBLE (-3750 1625);
FORCEPROP 1 LAST SIZE 1B
J 0
(-3100 1500);
DISPLAY 1.170213 (-3100 1500);
PAINT AQUA (-3100 1500);
DISPLAY INVISIBLE (-3100 1500);
FORCEPROP 1 LAST VOLTAGE 0
J 0
(-3175 1550);
PAINT SKYBLUE (-3175 1550);
DISPLAY INVISIBLE (-3175 1550);
FORCEPROP 1 LAST PATH I44
J 0
(-3100 1550);
DISPLAY 0.872340 (-3100 1550);
PAINT AQUA (-3100 1550);
DISPLAY INVISIBLE (-3100 1550);
FORCEPROP 2 LAST CDS_LIB mstr_symbols
J 0
(-3175 1550);
PAINT ORANGE (-3175 1550);
DISPLAY INVISIBLE (-3175 1550);
FORCEPROP 1 LAST BODY_TYPE PLUMBING
J 0
(-3220 1507);
DISPLAY 0.340426 (-3220 1507);
PAINT GREEN (-3220 1507);
DISPLAY INVISIBLE (-3220 1507);
FORCEPROP 1 LAST HDL_POWER GND
J 0
(-3175 1700);
DISPLAY 1.170213 (-3175 1700);
PAINT GREEN (-3175 1700);
DISPLAY INVISIBLE (-3175 1700);
FORCEADD RES..2
(-4350 4275);
FORCEPROP 1 LASTPIN (-4350 4175) $PN 2
J 0
(-4345 4185);
DISPLAY 0.617021 (-4345 4185);
PAINT WHITE (-4345 4185);
FORCEPROP 1 LAST WATTAGE 1/16W
J 0
(-4310 4250);
DISPLAY 0.617021 (-4310 4250);
PAINT SKYBLUE (-4310 4250);
FORCEPROP 1 LAST MATERIAL CHIP
J 0
(-4310 4200);
DISPLAY 0.617021 (-4310 4200);
PAINT SKYBLUE (-4310 4200);
FORCEPROP 1 LAST PACK_TYPE 0402
J 0
(-4310 4100);
DISPLAY 0.617021 (-4310 4100);
PAINT SKYBLUE (-4310 4100);
FORCEPROP 1 LAST TOLERANCE 5%
J 0
(-4305 4300);
DISPLAY 0.617021 (-4305 4300);
PAINT SKYBLUE (-4305 4300);
FORCEPROP 1 LAST VALUE 0.0
J 0
(-4305 4350);
DISPLAY 0.617021 (-4305 4350);
PAINT SKYBLUE (-4305 4350);
FORCEPROP 1 LASTPIN (-4350 4375) $PN 1
J 0
(-4345 4337);
DISPLAY 0.617021 (-4345 4337);
PAINT WHITE (-4345 4337);
FORCEPROP 1 LAST LOCATION R1C14
J 0
(-4305 4400);
DISPLAY 0.617021 (-4305 4400);
PAINT AQUA (-4305 4400);
FORCEPROP 1 LAST PART_NUMBER G21497-005
J 0
(-4310 4150);
DISPLAY 0.617021 (-4310 4150);
PAINT BLUE (-4310 4150);
FORCEPROP 2 LAST CDS_LIB mstr_discrete
J 0
(-4350 4275);
PAINT ORANGE (-4350 4275);
DISPLAY INVISIBLE (-4350 4275);
FORCEPROP 2 LAST SEC_TYPE 0402
J 0
(-4300 4500);
DISPLAY 1.021277 (-4300 4500);
PAINT ORANGE (-4300 4500);
DISPLAY INVISIBLE (-4300 4500);
FORCEPROP 2 LAST SEC 1
J 0
(-4300 4500);
PAINT MONO (-4300 4500);
DISPLAY INVISIBLE (-4300 4500);
FORCEPROP 2 LAST CDS_LOCATION R1C14
J 0
(-4305 4400);
DISPLAY 0.617021 (-4305 4400);
PAINT AQUA (-4305 4400);
DISPLAY INVISIBLE (-4305 4400);
FORCEPROP 1 LAST PATH I46
J 0
(-4300 4450);
DISPLAY 0.978723 (-4300 4450);
PAINT WHITE (-4300 4450);
DISPLAY INVISIBLE (-4300 4450);
FORCEPROP 2 LAST ROOM PVCCIN_CPU1_VR
J 0
(-4300 4450);
DISPLAY 1.361702 (-4300 4450);
PAINT WHITE (-4300 4450);
DISPLAY INVISIBLE (-4300 4450);
FORCEADD PVCCIO_CPU1..1
(-5225 4875);
FORCEPROP 3 LASTPIN (-5225 4825) SIG_NAME PVCCIO_CPU1\g
J 0
(-5215 4835);
DISPLAY 0.659574 (-5215 4835);
PAINT MONO (-5215 4835);
DISPLAY INVISIBLE (-5215 4835);
FORCEPROP 1 LAST VOLTAGE 1.1V
J 0
(-5270 4832);
DISPLAY 0.340426 (-5270 4832);
PAINT SKYBLUE (-5270 4832);
DISPLAY INVISIBLE (-5270 4832);
FORCEPROP 1 LAST PATH I47
J 0
(-5175 4900);
DISPLAY 0.872340 (-5175 4900);
PAINT AQUA (-5175 4900);
DISPLAY INVISIBLE (-5175 4900);
FORCEPROP 2 LAST CDS_LIB mstr_symbols
J 0
(-5225 4875);
PAINT ORANGE (-5225 4875);
DISPLAY INVISIBLE (-5225 4875);
FORCEPROP 1 LAST BODY_TYPE PLUMBING
J 0
(-5270 4832);
DISPLAY 0.340426 (-5270 4832);
PAINT GREEN (-5270 4832);
DISPLAY INVISIBLE (-5270 4832);
FORCEPROP 1 LAST HDL_POWER PVCCIO_CPU1
J 1
(-5225 4925);
DISPLAY 0.872340 (-5225 4925);
PAINT GREEN (-5225 4925);
DISPLAY INVISIBLE (-5225 4925);
FORCEADD VCC_CORE..1
(-6150 4875);
FORCEPROP 3 LASTPIN (-6150 4825) SIG_NAME VR_FET_SW_P12V_STBY_PVCCIN_CPU1\g
J 0
(-6140 4835);
DISPLAY 0.659574 (-6140 4835);
PAINT MONO (-6140 4835);
DISPLAY INVISIBLE (-6140 4835);
FORCEPROP 1 LAST HDL_POWER VR_FET_SW_P12V_STBY_PVCCIN_CPU1
J 1
(-6150 4925);
DISPLAY 0.617021 (-6150 4925);
PAINT GREEN (-6150 4925);
FORCEPROP 2 LAST CDS_LIB mstr_symbols
J 0
(-6150 4875);
PAINT ORANGE (-6150 4875);
DISPLAY INVISIBLE (-6150 4875);
FORCEPROP 0 LAST VOLTAGE 12
J 0
(-6150 5025);
DISPLAY 1.021277 (-6150 5025);
PAINT SKYBLUE (-6150 5025);
DISPLAY INVISIBLE (-6150 5025);
FORCEPROP 0 LASTPIN (-6150 4825) VOLTAGE +3.3V
R 1
J 0
(-6150 4875);
DISPLAY 1.021277 (-6150 4875);
PAINT SKYBLUE (-6150 4875);
DISPLAY INVISIBLE (-6150 4875);
FORCEPROP 1 LAST PATH I48
J 0
(-6100 4900);
DISPLAY 0.872340 (-6100 4900);
PAINT AQUA (-6100 4900);
DISPLAY INVISIBLE (-6100 4900);
FORCEADD RES..2
(-6150 4575);
FORCEPROP 1 LASTPIN (-6150 4675) $PN 1
J 0
(-6145 4637);
DISPLAY 0.617021 (-6145 4637);
PAINT WHITE (-6145 4637);
FORCEPROP 1 LASTPIN (-6150 4475) $PN 2
J 0
(-6145 4485);
DISPLAY 0.617021 (-6145 4485);
PAINT WHITE (-6145 4485);
FORCEPROP 1 LAST WATTAGE 1/16W
J 0
(-6110 4550);
DISPLAY 0.617021 (-6110 4550);
PAINT SKYBLUE (-6110 4550);
FORCEPROP 1 LAST MATERIAL CHIP
J 0
(-6110 4500);
DISPLAY 0.617021 (-6110 4500);
PAINT SKYBLUE (-6110 4500);
FORCEPROP 1 LAST PACK_TYPE 0402
J 0
(-6110 4400);
DISPLAY 0.617021 (-6110 4400);
PAINT SKYBLUE (-6110 4400);
FORCEPROP 1 LAST PART_NUMBER G21796-160
J 0
(-6110 4450);
DISPLAY 0.617021 (-6110 4450);
PAINT BLUE (-6110 4450);
FORCEPROP 1 LAST TOLERANCE 1%
J 0
(-6105 4600);
DISPLAY 0.617021 (-6105 4600);
PAINT SKYBLUE (-6105 4600);
FORCEPROP 1 LAST VALUE 100.0K
J 0
(-6105 4650);
DISPLAY 0.617021 (-6105 4650);
PAINT SKYBLUE (-6105 4650);
FORCEPROP 1 LAST LOCATION R1C13
J 0
(-6105 4700);
DISPLAY 0.617021 (-6105 4700);
PAINT AQUA (-6105 4700);
FORCEPROP 2 LAST CDS_LIB mstr_discrete
J 0
(-6150 4575);
PAINT ORANGE (-6150 4575);
DISPLAY INVISIBLE (-6150 4575);
FORCEPROP 2 LAST ROOM PVCCIN_CPU1_VR
J 0
(-6100 4750);
DISPLAY 1.361702 (-6100 4750);
PAINT WHITE (-6100 4750);
DISPLAY INVISIBLE (-6100 4750);
FORCEPROP 1 LAST PATH I49
J 0
(-6100 4750);
DISPLAY 0.978723 (-6100 4750);
PAINT WHITE (-6100 4750);
DISPLAY INVISIBLE (-6100 4750);
FORCEPROP 2 LAST CDS_LOCATION R1C13
J 0
(-6105 4700);
DISPLAY 0.617021 (-6105 4700);
PAINT AQUA (-6105 4700);
DISPLAY INVISIBLE (-6105 4700);
FORCEPROP 2 LAST SEC 1
J 0
(-6100 4800);
DISPLAY 0.680851 (-6100 4800);
PAINT MONO (-6100 4800);
DISPLAY INVISIBLE (-6100 4800);
FORCEPROP 2 LAST SEC_TYPE 0402
J 0
(-6100 4800);
DISPLAY 1.021277 (-6100 4800);
PAINT ORANGE (-6100 4800);
DISPLAY INVISIBLE (-6100 4800);
FORCEADD OFFPAGE..2
(-550 3375);
FORCEPROP 2 LAST $XR0 190 
J 0
(-361 3375);
DISPLAY 0.638298 (-361 3375);
PAINT MONO (-361 3375);
FORCEPROP 2 LAST ROOM PVCCIN_CPU1_VR
J 0
(-975 3450);
DISPLAY 1.361702 (-975 3450);
PAINT WHITE (-975 3450);
DISPLAY INVISIBLE (-975 3450);
FORCEPROP 2 LAST CDS_LIB mstr_standard
J 0
(-550 3375);
PAINT ORANGE (-550 3375);
DISPLAY INVISIBLE (-550 3375);
FORCEPROP 2 LAST PATH I5
J 0
(-375 3450);
DISPLAY 1.021277 (-375 3450);
PAINT ORANGE (-375 3450);
DISPLAY INVISIBLE (-375 3450);
FORCEPROP 1 LAST OFFPAGE TRUE
J 0
(-225 3250);
DISPLAY 1.170213 (-225 3250);
PAINT GREEN (-225 3250);
DISPLAY INVISIBLE (-225 3250);
FORCEPROP 1 LAST COMMENT_BODY TRUE
J 0
(-595 3280);
DISPLAY 1.170213 (-595 3280);
PAINT PEACH (-595 3280);
DISPLAY INVISIBLE (-595 3280);
FORCEADD OFFPAGE..2
R 2
(-7500 4425);
FORCEPROP 2 LAST $XR0 206 
J 0
(-7785 4425);
DISPLAY 0.638298 (-7785 4425);
PAINT MONO (-7785 4425);
FORCEPROP 2 LAST PATH I50
J 0
(-7775 4475);
DISPLAY 1.021277 (-7775 4475);
PAINT ORANGE (-7775 4475);
DISPLAY INVISIBLE (-7775 4475);
FORCEPROP 2 LAST ROOM PVCCIN_CPU1_VR
J 0
(-8050 4500);
DISPLAY 1.361702 (-8050 4500);
PAINT WHITE (-8050 4500);
DISPLAY INVISIBLE (-8050 4500);
FORCEPROP 2 LAST CDS_LIB mstr_standard
J 2
(-7500 4425);
PAINT ORANGE (-7500 4425);
DISPLAY INVISIBLE (-7500 4425);
FORCEPROP 1 LAST OFFPAGE TRUE
J 2
(-7825 4300);
DISPLAY 1.170213 (-7825 4300);
PAINT GREEN (-7825 4300);
DISPLAY INVISIBLE (-7825 4300);
FORCEPROP 1 LAST COMMENT_BODY TRUE
J 2
(-7455 4330);
DISPLAY 1.170213 (-7455 4330);
PAINT PEACH (-7455 4330);
DISPLAY INVISIBLE (-7455 4330);
FORCEADD RES..2
(-5650 4450);
FORCEPROP 1 LASTPIN (-5650 4550) $PN 1
J 0
(-5645 4512);
DISPLAY 0.617021 (-5645 4512);
PAINT WHITE (-5645 4512);
FORCEPROP 1 LASTPIN (-5650 4350) $PN 2
J 0
(-5645 4360);
DISPLAY 0.617021 (-5645 4360);
PAINT WHITE (-5645 4360);
FORCEPROP 1 LAST WATTAGE 1/16W
J 0
(-5610 4425);
DISPLAY 0.617021 (-5610 4425);
PAINT SKYBLUE (-5610 4425);
FORCEPROP 1 LAST MATERIAL CHIP
J 0
(-5610 4375);
DISPLAY 0.617021 (-5610 4375);
PAINT SKYBLUE (-5610 4375);
FORCEPROP 1 LAST PACK_TYPE 0402
J 0
(-5610 4275);
DISPLAY 0.617021 (-5610 4275);
PAINT SKYBLUE (-5610 4275);
FORCEPROP 1 LAST LOCATION R9P2
J 0
(-5605 4575);
DISPLAY 0.617021 (-5605 4575);
PAINT AQUA (-5605 4575);
FORCEPROP 1 LAST PART_NUMBER G21796-047
J 0
(-5610 4325);
DISPLAY 0.617021 (-5610 4325);
PAINT BLUE (-5610 4325);
FORCEPROP 1 LAST VALUE 49.9
J 0
(-5605 4525);
DISPLAY 0.617021 (-5605 4525);
PAINT SKYBLUE (-5605 4525);
FORCEPROP 1 LAST TOLERANCE 1%
J 0
(-5605 4475);
DISPLAY 0.617021 (-5605 4475);
PAINT SKYBLUE (-5605 4475);
FORCEPROP 2 LAST CDS_LIB mstr_discrete
J 0
(-5650 4450);
PAINT ORANGE (-5650 4450);
DISPLAY INVISIBLE (-5650 4450);
FORCEPROP 2 LAST CDS_LOCATION R9P2
J 0
(-5605 4575);
DISPLAY 0.617021 (-5605 4575);
PAINT AQUA (-5605 4575);
DISPLAY INVISIBLE (-5605 4575);
FORCEPROP 2 LAST ROOM PVCCIN_CPU1_VR
J 0
(-5600 4625);
DISPLAY 1.361702 (-5600 4625);
PAINT WHITE (-5600 4625);
DISPLAY INVISIBLE (-5600 4625);
FORCEPROP 1 LAST PATH I53
J 0
(-5600 4625);
DISPLAY 0.978723 (-5600 4625);
PAINT WHITE (-5600 4625);
DISPLAY INVISIBLE (-5600 4625);
FORCEPROP 2 LAST SEC_TYPE 0402
J 0
(-5600 4675);
DISPLAY 1.021277 (-5600 4675);
PAINT ORANGE (-5600 4675);
DISPLAY INVISIBLE (-5600 4675);
FORCEPROP 2 LAST SEC 1
J 0
(-5600 4675);
DISPLAY 0.680851 (-5600 4675);
PAINT MONO (-5600 4675);
DISPLAY INVISIBLE (-5600 4675);
FORCEADD RES..1
(-5375 3900);
FORCEPROP 1 LASTPIN (-5475 3900) $PN 1
J 0
(-5463 3912);
DISPLAY 0.617021 (-5463 3912);
PAINT WHITE (-5463 3912);
FORCEPROP 1 LAST WATTAGE 1/16W
J 2
(-5325 3925);
DISPLAY 0.617021 (-5325 3925);
PAINT SKYBLUE (-5325 3925);
FORCEPROP 1 LAST VALUE 150.0
J 2
(-5375 3975);
DISPLAY 0.617021 (-5375 3975);
PAINT SKYBLUE (-5375 3975);
FORCEPROP 1 LAST PART_NUMBER G21796-009
J 0
(-5475 4025);
DISPLAY 0.617021 (-5475 4025);
PAINT BLUE (-5475 4025);
FORCEPROP 1 LAST TOLERANCE 1%
J 0
(-5325 3975);
DISPLAY 0.617021 (-5325 3975);
PAINT SKYBLUE (-5325 3975);
FORCEPROP 1 LAST PACK_TYPE 0402
J 0
(-5250 3975);
DISPLAY 0.617021 (-5250 3975);
PAINT SKYBLUE (-5250 3975);
FORCEPROP 1 LAST MATERIAL CHIP
J 0
(-5275 3925);
DISPLAY 0.617021 (-5275 3925);
PAINT SKYBLUE (-5275 3925);
FORCEPROP 1 LASTPIN (-5275 3900) $PN 2
J 0
(-5313 3912);
DISPLAY 0.617021 (-5313 3912);
PAINT WHITE (-5313 3912);
FORCEPROP 1 LAST LOCATION R1D9
J 0
(-5475 4075);
DISPLAY 0.617021 (-5475 4075);
PAINT AQUA (-5475 4075);
FORCEPROP 1 LAST PATH I54
J 0
(-5425 4050);
DISPLAY 0.978723 (-5425 4050);
PAINT WHITE (-5425 4050);
DISPLAY INVISIBLE (-5425 4050);
FORCEPROP 2 LAST CDS_LIB mstr_discrete
J 0
(-5375 3900);
PAINT ORANGE (-5375 3900);
DISPLAY INVISIBLE (-5375 3900);
FORCEPROP 2 LAST CDS_LOCATION R1D9
J 0
(-5475 4075);
DISPLAY 0.617021 (-5475 4075);
PAINT AQUA (-5475 4075);
DISPLAY INVISIBLE (-5475 4075);
FORCEPROP 2 LAST CDS_SEC 1
J 0
(-5475 4125);
PAINT MONO (-5475 4125);
DISPLAY INVISIBLE (-5475 4125);
FORCEPROP 2 LAST $SEC 1
J 0
(-5475 4125);
PAINT MONO (-5475 4125);
DISPLAY INVISIBLE (-5475 4125);
FORCEPROP 2 LAST ROOM PVCCIN_CPU1_VR
J 0
(-5475 4125);
DISPLAY 1.361702 (-5475 4125);
PAINT WHITE (-5475 4125);
DISPLAY INVISIBLE (-5475 4125);
FORCEADD RES..2
(-6150 4225);
FORCEPROP 1 LAST PACK_TYPE 0402
J 0
(-6110 4050);
DISPLAY 0.617021 (-6110 4050);
PAINT SKYBLUE (-6110 4050);
FORCEPROP 1 LASTPIN (-6150 4325) $PN 1
J 0
(-6145 4287);
DISPLAY 0.617021 (-6145 4287);
PAINT WHITE (-6145 4287);
FORCEPROP 1 LASTPIN (-6150 4125) $PN 2
J 0
(-6145 4135);
DISPLAY 0.617021 (-6145 4135);
PAINT WHITE (-6145 4135);
FORCEPROP 1 LAST MATERIAL CHIP
J 0
(-6110 4150);
DISPLAY 0.617021 (-6110 4150);
PAINT SKYBLUE (-6110 4150);
FORCEPROP 1 LAST WATTAGE 1/16W
J 0
(-6110 4200);
DISPLAY 0.617021 (-6110 4200);
PAINT SKYBLUE (-6110 4200);
FORCEPROP 1 LAST TOLERANCE 1%
J 0
(-6105 4250);
DISPLAY 0.617021 (-6105 4250);
PAINT SKYBLUE (-6105 4250);
FORCEPROP 1 LAST VALUE 1.5K
J 0
(-6105 4300);
DISPLAY 0.617021 (-6105 4300);
PAINT SKYBLUE (-6105 4300);
FORCEPROP 1 LAST LOCATION R1C16
J 0
(-6105 4350);
DISPLAY 0.617021 (-6105 4350);
PAINT AQUA (-6105 4350);
FORCEPROP 1 LAST PART_NUMBER G21796-003
J 0
(-6110 4100);
DISPLAY 0.617021 (-6110 4100);
PAINT BLUE (-6110 4100);
FORCEPROP 2 LAST CDS_LIB mstr_discrete
J 0
(-6150 4225);
PAINT ORANGE (-6150 4225);
DISPLAY INVISIBLE (-6150 4225);
FORCEPROP 2 LAST SEC_TYPE 0402
J 0
(-6100 4450);
DISPLAY 1.021277 (-6100 4450);
PAINT ORANGE (-6100 4450);
DISPLAY INVISIBLE (-6100 4450);
FORCEPROP 2 LAST ROOM PVCCIN_CPU1_VR
J 0
(-6100 4400);
DISPLAY 1.361702 (-6100 4400);
PAINT WHITE (-6100 4400);
DISPLAY INVISIBLE (-6100 4400);
FORCEPROP 1 LAST PATH I56
J 0
(-6100 4400);
DISPLAY 0.978723 (-6100 4400);
PAINT WHITE (-6100 4400);
DISPLAY INVISIBLE (-6100 4400);
FORCEPROP 2 LAST CDS_LOCATION R1C16
J 0
(-6105 4350);
DISPLAY 0.617021 (-6105 4350);
PAINT AQUA (-6105 4350);
DISPLAY INVISIBLE (-6105 4350);
FORCEPROP 2 LAST SEC 1
J 0
(-6100 4450);
DISPLAY 0.680851 (-6100 4450);
PAINT MONO (-6100 4450);
DISPLAY INVISIBLE (-6100 4450);
FORCEADD GND..1
(-6150 3975);
FORCEPROP 3 LASTPIN (-6150 4025) SIG_NAME GND\g
J 0
(-6140 4035);
DISPLAY 0.659574 (-6140 4035);
PAINT MONO (-6140 4035);
DISPLAY INVISIBLE (-6140 4035);
FORCEPROP 1 LAST VOLTAGE 0
J 0
(-6150 3975);
PAINT SKYBLUE (-6150 3975);
DISPLAY INVISIBLE (-6150 3975);
FORCEPROP 2 LAST CDS_LIB mstr_symbols
J 0
(-6150 3975);
PAINT ORANGE (-6150 3975);
DISPLAY INVISIBLE (-6150 3975);
FORCEPROP 1 LAST PATH I57
J 0
(-6075 3975);
DISPLAY 0.872340 (-6075 3975);
PAINT AQUA (-6075 3975);
DISPLAY INVISIBLE (-6075 3975);
FORCEPROP 1 LAST SIZE 1B
J 0
(-6075 3925);
DISPLAY 1.170213 (-6075 3925);
PAINT AQUA (-6075 3925);
DISPLAY INVISIBLE (-6075 3925);
FORCEPROP 2 LAST ROOM PVCCIN_CPU1_VR
J 0
(-6725 4050);
DISPLAY 1.361702 (-6725 4050);
PAINT WHITE (-6725 4050);
DISPLAY INVISIBLE (-6725 4050);
FORCEPROP 1 LAST BODY_TYPE PLUMBING
J 0
(-6195 3932);
DISPLAY 0.340426 (-6195 3932);
PAINT GREEN (-6195 3932);
DISPLAY INVISIBLE (-6195 3932);
FORCEPROP 1 LAST HDL_POWER GND
J 0
(-6150 4125);
DISPLAY 1.170213 (-6150 4125);
PAINT GREEN (-6150 4125);
DISPLAY INVISIBLE (-6150 4125);
FORCEADD RES..2
R 2
(-3075 4000);
FORCEPROP 1 LASTPIN (-3075 4100) $PN 1
J 2
(-3080 4062);
DISPLAY 0.617021 (-3080 4062);
PAINT WHITE (-3080 4062);
FORCEPROP 1 LASTPIN (-3075 3900) $PN 2
J 2
(-3080 3910);
DISPLAY 0.617021 (-3080 3910);
PAINT WHITE (-3080 3910);
FORCEPROP 1 LAST WATTAGE 1/16W
J 2
(-3115 3975);
DISPLAY 0.617021 (-3115 3975);
PAINT SKYBLUE (-3115 3975);
FORCEPROP 1 LAST MATERIAL CHIP
J 2
(-3115 3925);
DISPLAY 0.617021 (-3115 3925);
PAINT SKYBLUE (-3115 3925);
FORCEPROP 1 LAST PACK_TYPE 0402
J 2
(-3115 3825);
DISPLAY 0.617021 (-3115 3825);
PAINT SKYBLUE (-3115 3825);
FORCEPROP 1 LAST TOLERANCE 1%
J 2
(-3120 4025);
DISPLAY 0.617021 (-3120 4025);
PAINT SKYBLUE (-3120 4025);
FORCEPROP 1 LAST PART_NUMBER G21796-026
J 2
(-3115 3875);
DISPLAY 0.617021 (-3115 3875);
PAINT BLUE (-3115 3875);
FORCEPROP 1 LAST VALUE 1.00K
J 2
(-3120 4075);
DISPLAY 0.617021 (-3120 4075);
PAINT SKYBLUE (-3120 4075);
FORCEPROP 1 LAST LOCATION R1D6
J 2
(-3120 4125);
DISPLAY 0.617021 (-3120 4125);
PAINT AQUA (-3120 4125);
FORCEPROP 2 LAST CDS_LIB mstr_discrete
J 0
(-3075 4000);
PAINT ORANGE (-3075 4000);
DISPLAY INVISIBLE (-3075 4000);
FORCEPROP 2 LAST SEC_TYPE 0402
J 2
(-3125 4225);
DISPLAY 1.021277 (-3125 4225);
PAINT ORANGE (-3125 4225);
DISPLAY INVISIBLE (-3125 4225);
FORCEPROP 2 LAST SEC 1
J 2
(-3125 4225);
DISPLAY 0.680851 (-3125 4225);
PAINT MONO (-3125 4225);
DISPLAY INVISIBLE (-3125 4225);
FORCEPROP 2 LAST CDS_LOCATION R1D6
J 2
(-3120 4125);
DISPLAY 0.617021 (-3120 4125);
PAINT AQUA (-3120 4125);
DISPLAY INVISIBLE (-3120 4125);
FORCEPROP 1 LAST PATH I6
J 2
(-3125 4175);
DISPLAY 0.978723 (-3125 4175);
PAINT WHITE (-3125 4175);
DISPLAY INVISIBLE (-3125 4175);
FORCEPROP 2 LAST ROOM PVCCIN_CPU1_VR
J 2
(-3125 4175);
DISPLAY 1.361702 (-3125 4175);
PAINT WHITE (-3125 4175);
DISPLAY INVISIBLE (-3125 4175);
FORCEADD GND..1
(-4500 575);
FORCEPROP 3 LASTPIN (-4500 625) SIG_NAME GND\g
J 0
(-4490 635);
DISPLAY 0.659574 (-4490 635);
PAINT MONO (-4490 635);
DISPLAY INVISIBLE (-4490 635);
FORCEPROP 2 LAST ROOM PVCCIN_CPU1_VR
J 0
(-5075 650);
DISPLAY 1.361702 (-5075 650);
PAINT WHITE (-5075 650);
DISPLAY INVISIBLE (-5075 650);
FORCEPROP 1 LAST PATH I65
J 0
(-4425 575);
DISPLAY 0.872340 (-4425 575);
PAINT AQUA (-4425 575);
DISPLAY INVISIBLE (-4425 575);
FORCEPROP 1 LAST SIZE 1B
J 0
(-4425 525);
DISPLAY 1.170213 (-4425 525);
PAINT AQUA (-4425 525);
DISPLAY INVISIBLE (-4425 525);
FORCEPROP 2 LAST CDS_LIB mstr_symbols
J 0
(-4500 575);
PAINT ORANGE (-4500 575);
DISPLAY INVISIBLE (-4500 575);
FORCEPROP 1 LAST VOLTAGE 0
J 0
(-4500 575);
PAINT SKYBLUE (-4500 575);
DISPLAY INVISIBLE (-4500 575);
FORCEPROP 1 LAST BODY_TYPE PLUMBING
J 0
(-4545 532);
DISPLAY 0.340426 (-4545 532);
PAINT GREEN (-4545 532);
DISPLAY INVISIBLE (-4545 532);
FORCEPROP 1 LAST HDL_POWER GND
J 0
(-4500 725);
DISPLAY 1.170213 (-4500 725);
PAINT GREEN (-4500 725);
DISPLAY INVISIBLE (-4500 725);
FORCEADD GND..1
(-4825 525);
FORCEPROP 3 LASTPIN (-4825 575) SIG_NAME GND\g
J 0
(-4815 585);
DISPLAY 0.659574 (-4815 585);
PAINT MONO (-4815 585);
DISPLAY INVISIBLE (-4815 585);
FORCEPROP 2 LAST ROOM PVCCIN_CPU1_VR
J 0
(-5400 600);
DISPLAY 1.361702 (-5400 600);
PAINT WHITE (-5400 600);
DISPLAY INVISIBLE (-5400 600);
FORCEPROP 1 LAST SIZE 1B
J 0
(-4750 475);
DISPLAY 1.170213 (-4750 475);
PAINT AQUA (-4750 475);
DISPLAY INVISIBLE (-4750 475);
FORCEPROP 1 LAST PATH I67
J 0
(-4750 525);
DISPLAY 0.872340 (-4750 525);
PAINT AQUA (-4750 525);
DISPLAY INVISIBLE (-4750 525);
FORCEPROP 2 LAST CDS_LIB mstr_symbols
J 0
(-4825 525);
PAINT ORANGE (-4825 525);
DISPLAY INVISIBLE (-4825 525);
FORCEPROP 1 LAST VOLTAGE 0
J 0
(-4825 525);
PAINT SKYBLUE (-4825 525);
DISPLAY INVISIBLE (-4825 525);
FORCEPROP 1 LAST BODY_TYPE PLUMBING
J 0
(-4870 482);
DISPLAY 0.340426 (-4870 482);
PAINT GREEN (-4870 482);
DISPLAY INVISIBLE (-4870 482);
FORCEPROP 1 LAST HDL_POWER GND
J 0
(-4825 675);
DISPLAY 1.170213 (-4825 675);
PAINT GREEN (-4825 675);
DISPLAY INVISIBLE (-4825 675);
FORCEADD CAP..1
(-5650 2075);
FORCEPROP 1 LAST VOLTAGE 50V
J 0
(-6150 1950);
DISPLAY 0.617021 (-6150 1950);
PAINT SKYBLUE (-6150 1950);
FORCEPROP 1 LAST MATERIAL X7R
J 0
(-6000 1950);
DISPLAY 0.617021 (-6000 1950);
PAINT SKYBLUE (-6000 1950);
FORCEPROP 1 LAST PACK_TYPE 0402LF
J 0
(-5875 1950);
DISPLAY 0.617021 (-5875 1950);
PAINT SKYBLUE (-5875 1950);
FORCEPROP 1 LASTPIN (-5650 1975) $PN 2
J 0
(-5640 1955);
DISPLAY 0.617021 (-5640 1955);
PAINT WHITE (-5640 1955);
FORCEPROP 1 LAST TOLERANCE 10%
J 0
(-5825 2025);
DISPLAY 0.617021 (-5825 2025);
PAINT SKYBLUE (-5825 2025);
FORCEPROP 1 LAST VALUE 220PF
J 0
(-6025 2025);
DISPLAY 0.617021 (-6025 2025);
PAINT SKYBLUE (-6025 2025);
FORCEPROP 1 LAST PART_NUMBER A36096-050
J 0
(-6025 2075);
DISPLAY 0.617021 (-6025 2075);
PAINT BLUE (-6025 2075);
FORCEPROP 1 LAST LOCATION C1C16
J 0
(-5900 2125);
DISPLAY 0.617021 (-5900 2125);
PAINT AQUA (-5900 2125);
FORCEPROP 1 LASTPIN (-5650 2175) $PN 1
J 0
(-5640 2155);
DISPLAY 0.617021 (-5640 2155);
PAINT WHITE (-5640 2155);
FORCEPROP 2 LAST ROOM PVCCIN_CPU1_VR
J 0
(-5900 2175);
DISPLAY 1.361702 (-5900 2175);
PAINT WHITE (-5900 2175);
DISPLAY INVISIBLE (-5900 2175);
FORCEPROP 2 LAST CDS_LOCATION C1C16
J 0
(-5900 2125);
DISPLAY 0.617021 (-5900 2125);
PAINT AQUA (-5900 2125);
DISPLAY INVISIBLE (-5900 2125);
FORCEPROP 2 LAST CDS_LIB mstr_discrete
J 0
(-5650 2075);
PAINT ORANGE (-5650 2075);
DISPLAY INVISIBLE (-5650 2075);
FORCEPROP 2 LAST SEC_TYPE 0402LF
J 0
(-5600 2275);
DISPLAY 1.021277 (-5600 2275);
PAINT ORANGE (-5600 2275);
DISPLAY INVISIBLE (-5600 2275);
FORCEPROP 1 LAST PATH I68
J 0
(-5600 2225);
DISPLAY 0.978723 (-5600 2225);
PAINT WHITE (-5600 2225);
DISPLAY INVISIBLE (-5600 2225);
FORCEPROP 2 LAST NO_XNET_CONNECTION 1
J 0
(-5600 2275);
PAINT MONO (-5600 2275);
DISPLAY INVISIBLE (-5600 2275);
FORCEPROP 2 LAST SEC 1
J 0
(-5600 2275);
DISPLAY 0.680851 (-5600 2275);
PAINT MONO (-5600 2275);
DISPLAY INVISIBLE (-5600 2275);
FORCEADD CAP..1
(-5925 1275);
FORCEPROP 1 LASTPIN (-5925 1175) $PN 2
J 0
(-5915 1155);
DISPLAY 0.617021 (-5915 1155);
PAINT WHITE (-5915 1155);
FORCEPROP 1 LASTPIN (-5925 1375) $PN 1
J 0
(-5915 1355);
DISPLAY 0.617021 (-5915 1355);
PAINT WHITE (-5915 1355);
FORCEPROP 1 LAST VOLTAGE 50V
J 0
(-5875 1275);
DISPLAY 0.617021 (-5875 1275);
PAINT SKYBLUE (-5875 1275);
FORCEPROP 1 LAST MATERIAL X7R
J 0
(-5750 1275);
DISPLAY 0.617021 (-5750 1275);
PAINT SKYBLUE (-5750 1275);
FORCEPROP 1 LAST LOCATION C1C10
J 0
(-5875 1375);
DISPLAY 0.617021 (-5875 1375);
PAINT AQUA (-5875 1375);
FORCEPROP 1 LAST VALUE 220PF
J 0
(-5875 1325);
DISPLAY 0.617021 (-5875 1325);
PAINT SKYBLUE (-5875 1325);
FORCEPROP 1 LAST PACK_TYPE 0402LF
J 0
(-5875 1175);
DISPLAY 0.617021 (-5875 1175);
PAINT SKYBLUE (-5875 1175);
FORCEPROP 1 LAST TOLERANCE 10%
J 0
(-5700 1325);
DISPLAY 0.617021 (-5700 1325);
PAINT SKYBLUE (-5700 1325);
FORCEPROP 1 LAST PART_NUMBER A36096-050
J 0
(-5875 1225);
DISPLAY 0.617021 (-5875 1225);
PAINT BLUE (-5875 1225);
FORCEPROP 2 LAST CDS_LIB mstr_discrete
J 0
(-5925 1275);
PAINT ORANGE (-5925 1275);
DISPLAY INVISIBLE (-5925 1275);
FORCEPROP 2 LAST ROOM PVCCIN_CPU1_VR
J 0
(-5875 1425);
DISPLAY 1.361702 (-5875 1425);
PAINT WHITE (-5875 1425);
DISPLAY INVISIBLE (-5875 1425);
FORCEPROP 1 LAST PATH I69
J 0
(-5875 1425);
DISPLAY 0.978723 (-5875 1425);
PAINT WHITE (-5875 1425);
DISPLAY INVISIBLE (-5875 1425);
FORCEPROP 2 LAST CDS_LOCATION C1C10
J 0
(-5875 1375);
DISPLAY 0.617021 (-5875 1375);
PAINT AQUA (-5875 1375);
DISPLAY INVISIBLE (-5875 1375);
FORCEPROP 2 LAST SEC_TYPE 0402LF
J 0
(-5875 1475);
DISPLAY 1.021277 (-5875 1475);
PAINT ORANGE (-5875 1475);
DISPLAY INVISIBLE (-5875 1475);
FORCEPROP 2 LAST SEC 1
J 0
(-5875 1475);
DISPLAY 0.680851 (-5875 1475);
PAINT MONO (-5875 1475);
DISPLAY INVISIBLE (-5875 1475);
FORCEADD RES..2
(-2050 4100);
FORCEPROP 1 LASTPIN (-2050 4000) $PN 2
J 0
(-2045 4010);
DISPLAY 0.617021 (-2045 4010);
PAINT WHITE (-2045 4010);
FORCEPROP 1 LAST MATERIAL CHIP
J 0
(-2010 4025);
DISPLAY 0.617021 (-2010 4025);
PAINT SKYBLUE (-2010 4025);
FORCEPROP 1 LAST PACK_TYPE 0402
J 0
(-2010 3925);
DISPLAY 0.617021 (-2010 3925);
PAINT SKYBLUE (-2010 3925);
FORCEPROP 1 LAST PART_NUMBER G21796-311
J 0
(-2010 3975);
DISPLAY 0.617021 (-2010 3975);
PAINT BLUE (-2010 3975);
FORCEPROP 1 LAST WATTAGE 1/16W
J 0
(-2010 4075);
DISPLAY 0.617021 (-2010 4075);
PAINT SKYBLUE (-2010 4075);
FORCEPROP 1 LASTPIN (-2050 4200) $PN 1
J 0
(-2045 4162);
DISPLAY 0.617021 (-2045 4162);
PAINT WHITE (-2045 4162);
FORCEPROP 1 LAST TOLERANCE 1.0%
J 0
(-2005 4125);
DISPLAY 0.617021 (-2005 4125);
PAINT SKYBLUE (-2005 4125);
FORCEPROP 1 LAST VALUE 2.26K
J 0
(-2005 4175);
DISPLAY 0.617021 (-2005 4175);
PAINT SKYBLUE (-2005 4175);
FORCEPROP 1 LAST LOCATION R1D7
J 0
(-2005 4225);
DISPLAY 0.617021 (-2005 4225);
PAINT AQUA (-2005 4225);
FORCEPROP 2 LAST ROOM PVCCIN_CPU1_VR
J 0
(-2000 4075);
DISPLAY 1.361702 (-2000 4075);
PAINT WHITE (-2000 4075);
DISPLAY INVISIBLE (-2000 4075);
FORCEPROP 2 LAST CDS_LIB mstr_discrete
J 0
(-2050 4100);
PAINT ORANGE (-2050 4100);
DISPLAY INVISIBLE (-2050 4100);
FORCEPROP 1 LAST PATH I7
J 0
(-2000 4275);
DISPLAY 0.978723 (-2000 4275);
PAINT WHITE (-2000 4275);
DISPLAY INVISIBLE (-2000 4275);
FORCEPROP 2 LAST CDS_LOCATION R1D7
J 0
(-2005 4225);
DISPLAY 0.617021 (-2005 4225);
PAINT AQUA (-2005 4225);
DISPLAY INVISIBLE (-2005 4225);
FORCEPROP 2 LAST SEC 1
J 0
(-2000 4325);
DISPLAY 0.680851 (-2000 4325);
PAINT MONO (-2000 4325);
DISPLAY INVISIBLE (-2000 4325);
FORCEPROP 2 LAST SEC_TYPE 0402
J 0
(-2000 4325);
DISPLAY 1.021277 (-2000 4325);
PAINT ORANGE (-2000 4325);
DISPLAY INVISIBLE (-2000 4325);
FORCEADD GND..1
(-5925 575);
FORCEPROP 3 LASTPIN (-5925 625) SIG_NAME GND\g
J 0
(-5915 635);
DISPLAY 0.659574 (-5915 635);
PAINT MONO (-5915 635);
DISPLAY INVISIBLE (-5915 635);
FORCEPROP 2 LAST ROOM PVCCIN_CPU1_VR
J 0
(-6500 650);
DISPLAY 1.361702 (-6500 650);
PAINT WHITE (-6500 650);
DISPLAY INVISIBLE (-6500 650);
FORCEPROP 1 LAST VOLTAGE 0
J 0
(-5925 575);
PAINT SKYBLUE (-5925 575);
DISPLAY INVISIBLE (-5925 575);
FORCEPROP 2 LAST CDS_LIB mstr_symbols
J 0
(-5925 575);
PAINT ORANGE (-5925 575);
DISPLAY INVISIBLE (-5925 575);
FORCEPROP 1 LAST SIZE 1B
J 0
(-5850 525);
DISPLAY 1.170213 (-5850 525);
PAINT AQUA (-5850 525);
DISPLAY INVISIBLE (-5850 525);
FORCEPROP 1 LAST PATH I70
J 0
(-5850 575);
DISPLAY 0.872340 (-5850 575);
PAINT AQUA (-5850 575);
DISPLAY INVISIBLE (-5850 575);
FORCEPROP 1 LAST BODY_TYPE PLUMBING
J 0
(-5970 532);
DISPLAY 0.340426 (-5970 532);
PAINT GREEN (-5970 532);
DISPLAY INVISIBLE (-5970 532);
FORCEPROP 1 LAST HDL_POWER GND
J 0
(-5925 725);
DISPLAY 1.170213 (-5925 725);
PAINT GREEN (-5925 725);
DISPLAY INVISIBLE (-5925 725);
FORCEADD CAP..1
R 2
(-6150 1000);
FORCEPROP 1 LAST PART_NUMBER A36096-050
J 2
(-6200 950);
DISPLAY 0.617021 (-6200 950);
PAINT BLUE (-6200 950);
FORCEPROP 1 LASTPIN (-6150 900) $PN 2
J 2
(-6160 880);
DISPLAY 0.617021 (-6160 880);
PAINT WHITE (-6160 880);
FORCEPROP 1 LAST PACK_TYPE 0402LF
J 2
(-6200 900);
DISPLAY 0.617021 (-6200 900);
PAINT SKYBLUE (-6200 900);
FORCEPROP 1 LAST MATERIAL X7R
J 2
(-6325 1000);
DISPLAY 0.617021 (-6325 1000);
PAINT SKYBLUE (-6325 1000);
FORCEPROP 1 LAST VOLTAGE 50V
J 2
(-6200 1000);
DISPLAY 0.617021 (-6200 1000);
PAINT SKYBLUE (-6200 1000);
FORCEPROP 1 LAST LOCATION C1C11
J 2
(-6200 1100);
DISPLAY 0.617021 (-6200 1100);
PAINT AQUA (-6200 1100);
FORCEPROP 1 LAST VALUE 220PF
J 2
(-6200 1050);
DISPLAY 0.617021 (-6200 1050);
PAINT SKYBLUE (-6200 1050);
FORCEPROP 1 LAST TOLERANCE 10%
J 2
(-6375 1050);
DISPLAY 0.617021 (-6375 1050);
PAINT SKYBLUE (-6375 1050);
FORCEPROP 1 LASTPIN (-6150 1100) $PN 1
J 2
(-6160 1080);
DISPLAY 0.617021 (-6160 1080);
PAINT WHITE (-6160 1080);
FORCEPROP 2 LAST CDS_LIB mstr_discrete
J 2
(-6150 1000);
PAINT ORANGE (-6150 1000);
DISPLAY INVISIBLE (-6150 1000);
FORCEPROP 2 LAST SEC_TYPE 0402LF
J 0
(-6200 1200);
DISPLAY 1.021277 (-6200 1200);
PAINT ORANGE (-6200 1200);
DISPLAY INVISIBLE (-6200 1200);
FORCEPROP 2 LAST SEC 1
J 0
(-6200 1200);
DISPLAY 0.680851 (-6200 1200);
PAINT MONO (-6200 1200);
DISPLAY INVISIBLE (-6200 1200);
FORCEPROP 2 LAST CDS_LOCATION C1C11
J 2
(-6200 1100);
DISPLAY 0.617021 (-6200 1100);
PAINT AQUA (-6200 1100);
DISPLAY INVISIBLE (-6200 1100);
FORCEPROP 1 LAST PATH I71
J 2
(-6200 1150);
DISPLAY 0.978723 (-6200 1150);
PAINT WHITE (-6200 1150);
DISPLAY INVISIBLE (-6200 1150);
FORCEPROP 2 LAST ROOM PVCCIN_CPU1_VR
J 0
(-6200 1150);
DISPLAY 1.361702 (-6200 1150);
PAINT WHITE (-6200 1150);
DISPLAY INVISIBLE (-6200 1150);
FORCEADD GND..1
(-6150 575);
FORCEPROP 3 LASTPIN (-6150 625) SIG_NAME GND\g
J 0
(-6140 635);
DISPLAY 0.659574 (-6140 635);
PAINT MONO (-6140 635);
DISPLAY INVISIBLE (-6140 635);
FORCEPROP 2 LAST ROOM PVCCIN_CPU1_VR
J 0
(-6725 650);
DISPLAY 1.361702 (-6725 650);
PAINT WHITE (-6725 650);
DISPLAY INVISIBLE (-6725 650);
FORCEPROP 2 LAST CDS_LIB mstr_symbols
J 0
(-6150 575);
PAINT ORANGE (-6150 575);
DISPLAY INVISIBLE (-6150 575);
FORCEPROP 1 LAST VOLTAGE 0
J 0
(-6150 575);
PAINT SKYBLUE (-6150 575);
DISPLAY INVISIBLE (-6150 575);
FORCEPROP 1 LAST SIZE 1B
J 0
(-6075 525);
DISPLAY 1.170213 (-6075 525);
PAINT AQUA (-6075 525);
DISPLAY INVISIBLE (-6075 525);
FORCEPROP 1 LAST PATH I72
J 0
(-6075 575);
DISPLAY 0.872340 (-6075 575);
PAINT AQUA (-6075 575);
DISPLAY INVISIBLE (-6075 575);
FORCEPROP 1 LAST BODY_TYPE PLUMBING
J 0
(-6195 532);
DISPLAY 0.340426 (-6195 532);
PAINT GREEN (-6195 532);
DISPLAY INVISIBLE (-6195 532);
FORCEPROP 1 LAST HDL_POWER GND
J 0
(-6150 725);
DISPLAY 1.170213 (-6150 725);
PAINT GREEN (-6150 725);
DISPLAY INVISIBLE (-6150 725);
FORCEADD CAP..1
R 2
(-6425 4200);
FORCEPROP 1 LAST PART_NUMBER A36096-046
J 2
(-6475 4050);
DISPLAY 0.617021 (-6475 4050);
PAINT BLUE (-6475 4050);
FORCEPROP 1 LAST PACK_TYPE 0402LF
J 2
(-6475 4000);
DISPLAY 0.617021 (-6475 4000);
PAINT SKYBLUE (-6475 4000);
FORCEPROP 1 LASTPIN (-6425 4100) $PN 2
J 2
(-6435 4080);
DISPLAY 0.617021 (-6435 4080);
PAINT WHITE (-6435 4080);
FORCEPROP 1 LASTPIN (-6425 4300) $PN 1
J 2
(-6435 4280);
DISPLAY 0.617021 (-6435 4280);
PAINT WHITE (-6435 4280);
FORCEPROP 1 LAST MATERIAL X7R
J 2
(-6475 4100);
DISPLAY 0.617021 (-6475 4100);
PAINT SKYBLUE (-6475 4100);
FORCEPROP 1 LAST LOCATION C1C8
J 2
(-6475 4300);
DISPLAY 0.617021 (-6475 4300);
PAINT AQUA (-6475 4300);
FORCEPROP 1 LAST VALUE 1000PF
J 2
(-6475 4250);
DISPLAY 0.617021 (-6475 4250);
PAINT SKYBLUE (-6475 4250);
FORCEPROP 1 LAST TOLERANCE 10%
J 2
(-6475 4150);
DISPLAY 0.617021 (-6475 4150);
PAINT SKYBLUE (-6475 4150);
FORCEPROP 1 LAST VOLTAGE 50V
J 2
(-6475 4200);
DISPLAY 0.617021 (-6475 4200);
PAINT SKYBLUE (-6475 4200);
FORCEPROP 2 LAST CDS_LIB mstr_discrete
J 2
(-6425 4200);
PAINT ORANGE (-6425 4200);
DISPLAY INVISIBLE (-6425 4200);
FORCEPROP 2 LAST CDS_LOCATION C1C8
J 2
(-6475 4300);
DISPLAY 0.617021 (-6475 4300);
PAINT AQUA (-6475 4300);
DISPLAY INVISIBLE (-6475 4300);
FORCEPROP 2 LAST ROOM PVCCIN_CPU1_VR
J 0
(-6475 4350);
DISPLAY 1.361702 (-6475 4350);
PAINT WHITE (-6475 4350);
DISPLAY INVISIBLE (-6475 4350);
FORCEPROP 1 LAST PATH I73
J 2
(-6475 4350);
DISPLAY 0.978723 (-6475 4350);
PAINT WHITE (-6475 4350);
DISPLAY INVISIBLE (-6475 4350);
FORCEPROP 2 LAST SEC 1
J 0
(-6475 4400);
DISPLAY 0.680851 (-6475 4400);
PAINT MONO (-6475 4400);
DISPLAY INVISIBLE (-6475 4400);
FORCEPROP 2 LAST SEC_TYPE 0402LF
J 0
(-6475 4400);
DISPLAY 1.021277 (-6475 4400);
PAINT ORANGE (-6475 4400);
DISPLAY INVISIBLE (-6475 4400);
FORCEADD GND..1
(-6425 3975);
FORCEPROP 3 LASTPIN (-6425 4025) SIG_NAME GND\g
J 0
(-6415 4035);
DISPLAY 0.659574 (-6415 4035);
PAINT MONO (-6415 4035);
DISPLAY INVISIBLE (-6415 4035);
FORCEPROP 1 LAST VOLTAGE 0
J 0
(-6425 3975);
PAINT SKYBLUE (-6425 3975);
DISPLAY INVISIBLE (-6425 3975);
FORCEPROP 2 LAST CDS_LIB mstr_symbols
J 0
(-6425 3975);
PAINT ORANGE (-6425 3975);
DISPLAY INVISIBLE (-6425 3975);
FORCEPROP 1 LAST SIZE 1B
J 0
(-6350 3925);
DISPLAY 1.170213 (-6350 3925);
PAINT AQUA (-6350 3925);
DISPLAY INVISIBLE (-6350 3925);
FORCEPROP 1 LAST PATH I74
J 0
(-6350 3975);
DISPLAY 0.872340 (-6350 3975);
PAINT AQUA (-6350 3975);
DISPLAY INVISIBLE (-6350 3975);
FORCEPROP 2 LAST ROOM PVCCIN_CPU1_VR
J 0
(-7000 4050);
DISPLAY 1.361702 (-7000 4050);
PAINT WHITE (-7000 4050);
DISPLAY INVISIBLE (-7000 4050);
FORCEPROP 1 LAST BODY_TYPE PLUMBING
J 0
(-6470 3932);
DISPLAY 0.340426 (-6470 3932);
PAINT GREEN (-6470 3932);
DISPLAY INVISIBLE (-6470 3932);
FORCEPROP 1 LAST HDL_POWER GND
J 0
(-6425 4125);
DISPLAY 1.170213 (-6425 4125);
PAINT GREEN (-6425 4125);
DISPLAY INVISIBLE (-6425 4125);
FORCEADD RES..1
(-6350 2075);
FORCEPROP 1 LAST VALUE 10.0
J 2
(-6375 1975);
DISPLAY 0.617021 (-6375 1975);
PAINT SKYBLUE (-6375 1975);
FORCEPROP 1 LAST TOLERANCE 1%
J 0
(-6350 1975);
DISPLAY 0.617021 (-6350 1975);
PAINT SKYBLUE (-6350 1975);
FORCEPROP 1 LAST MATERIAL CHIP
J 0
(-6350 1925);
DISPLAY 0.617021 (-6350 1925);
PAINT SKYBLUE (-6350 1925);
FORCEPROP 1 LAST WATTAGE 1/16W
J 2
(-6375 1925);
DISPLAY 0.617021 (-6375 1925);
PAINT SKYBLUE (-6375 1925);
FORCEPROP 1 LAST PACK_TYPE 0402
J 0
(-6450 2025);
DISPLAY 0.617021 (-6450 2025);
PAINT SKYBLUE (-6450 2025);
FORCEPROP 1 LASTPIN (-6450 2075) $PN 1
J 0
(-6438 2087);
DISPLAY 0.617021 (-6438 2087);
PAINT WHITE (-6438 2087);
FORCEPROP 2 LAST NO_XNET_CONNECTION 1
J 0
(-6400 2275);
PAINT MONO (-6400 2275);
FORCEPROP 1 LAST LOCATION R1C21
J 0
(-6400 2125);
DISPLAY 0.617021 (-6400 2125);
PAINT AQUA (-6400 2125);
FORCEPROP 1 LASTPIN (-6250 2075) $PN 2
J 0
(-6288 2087);
DISPLAY 0.617021 (-6288 2087);
PAINT WHITE (-6288 2087);
FORCEPROP 1 LAST PART_NUMBER G21796-066
J 0
(-6400 2175);
DISPLAY 0.617021 (-6400 2175);
PAINT BLUE (-6400 2175);
FORCEPROP 2 LAST ROOM PVCCIN_CPU1_VR
J 0
(-6400 2225);
DISPLAY 1.021277 (-6400 2225);
PAINT WHITE (-6400 2225);
DISPLAY INVISIBLE (-6400 2225);
FORCEPROP 1 LAST PATH I77
J 0
(-6400 2225);
DISPLAY 0.978723 (-6400 2225);
PAINT WHITE (-6400 2225);
DISPLAY INVISIBLE (-6400 2225);
FORCEPROP 2 LAST CDS_LOCATION R1C21
J 0
(-6400 2125);
DISPLAY 0.617021 (-6400 2125);
PAINT AQUA (-6400 2125);
DISPLAY INVISIBLE (-6400 2125);
FORCEPROP 2 LAST SEC 1
J 0
(-6400 2275);
DISPLAY 0.680851 (-6400 2275);
PAINT MONO (-6400 2275);
DISPLAY INVISIBLE (-6400 2275);
FORCEPROP 2 LAST SEC_TYPE 0402
J 0
(-6400 2275);
DISPLAY 1.021277 (-6400 2275);
PAINT ORANGE (-6400 2275);
DISPLAY INVISIBLE (-6400 2275);
FORCEPROP 2 LAST CDS_LIB mstr_discrete
J 0
(-6350 2075);
PAINT MONO (-6350 2075);
DISPLAY INVISIBLE (-6350 2075);
FORCEADD CAP..1
(-6550 2375);
FORCEPROP 1 LASTPIN (-6550 2275) $PN 2
J 0
(-6540 2255);
DISPLAY 0.617021 (-6540 2255);
PAINT WHITE (-6540 2255);
FORCEPROP 1 LAST VOLTAGE 50V
J 0
(-6500 2375);
DISPLAY 0.617021 (-6500 2375);
PAINT SKYBLUE (-6500 2375);
FORCEPROP 1 LASTPIN (-6550 2475) $PN 1
J 0
(-6540 2455);
DISPLAY 0.617021 (-6540 2455);
PAINT WHITE (-6540 2455);
FORCEPROP 1 LAST PACK_TYPE 0402LF
J 0
(-6500 2275);
DISPLAY 0.617021 (-6500 2275);
PAINT SKYBLUE (-6500 2275);
FORCEPROP 1 LAST VALUE 220PF
J 0
(-6500 2425);
DISPLAY 0.617021 (-6500 2425);
PAINT SKYBLUE (-6500 2425);
FORCEPROP 1 LAST PART_NUMBER A36096-050
J 0
(-6500 2325);
DISPLAY 0.617021 (-6500 2325);
PAINT BLUE (-6500 2325);
FORCEPROP 1 LAST LOCATION C1D1
J 0
(-6500 2475);
DISPLAY 0.617021 (-6500 2475);
PAINT AQUA (-6500 2475);
FORCEPROP 1 LAST TOLERANCE 10%
J 0
(-6325 2425);
DISPLAY 0.617021 (-6325 2425);
PAINT SKYBLUE (-6325 2425);
FORCEPROP 1 LAST MATERIAL X7R
J 0
(-6375 2375);
DISPLAY 0.617021 (-6375 2375);
PAINT SKYBLUE (-6375 2375);
FORCEPROP 2 LAST NO_XNET_CONNECTION 1
J 0
(-6500 2575);
PAINT MONO (-6500 2575);
FORCEPROP 2 LAST CDS_LIB mstr_discrete
J 0
(-6550 2375);
PAINT ORANGE (-6550 2375);
DISPLAY INVISIBLE (-6550 2375);
FORCEPROP 2 LAST CDS_LOCATION C1D1
J 0
(-6500 2475);
DISPLAY 0.617021 (-6500 2475);
PAINT AQUA (-6500 2475);
DISPLAY INVISIBLE (-6500 2475);
FORCEPROP 2 LAST ROOM PVCCIN_CPU1_VR
J 0
(-6500 2525);
DISPLAY 1.361702 (-6500 2525);
PAINT WHITE (-6500 2525);
DISPLAY INVISIBLE (-6500 2525);
FORCEPROP 1 LAST PATH I78
J 0
(-6500 2525);
DISPLAY 0.978723 (-6500 2525);
PAINT WHITE (-6500 2525);
DISPLAY INVISIBLE (-6500 2525);
FORCEPROP 2 LAST SEC 1
J 0
(-6500 2575);
DISPLAY 0.680851 (-6500 2575);
PAINT MONO (-6500 2575);
DISPLAY INVISIBLE (-6500 2575);
FORCEPROP 2 LAST SEC_TYPE 0402LF
J 0
(-6500 2575);
DISPLAY 1.021277 (-6500 2575);
PAINT ORANGE (-6500 2575);
DISPLAY INVISIBLE (-6500 2575);
FORCEADD RES..1
(-6775 2575);
FORCEPROP 1 LAST MATERIAL CHIP
J 0
(-6775 2425);
DISPLAY 0.617021 (-6775 2425);
PAINT SKYBLUE (-6775 2425);
FORCEPROP 1 LAST PACK_TYPE 0402
J 0
(-6850 2525);
DISPLAY 0.617021 (-6850 2525);
PAINT SKYBLUE (-6850 2525);
FORCEPROP 1 LAST TOLERANCE 1%
J 0
(-6775 2475);
DISPLAY 0.617021 (-6775 2475);
PAINT SKYBLUE (-6775 2475);
FORCEPROP 1 LAST VALUE 10.0
J 2
(-6800 2475);
DISPLAY 0.617021 (-6800 2475);
PAINT SKYBLUE (-6800 2475);
FORCEPROP 1 LAST WATTAGE 1/16W
J 2
(-6800 2425);
DISPLAY 0.617021 (-6800 2425);
PAINT SKYBLUE (-6800 2425);
FORCEPROP 1 LASTPIN (-6875 2575) $PN 1
J 0
(-6863 2587);
DISPLAY 0.617021 (-6863 2587);
PAINT WHITE (-6863 2587);
FORCEPROP 1 LAST LOCATION R1D4
J 0
(-6825 2625);
DISPLAY 0.617021 (-6825 2625);
PAINT AQUA (-6825 2625);
FORCEPROP 1 LASTPIN (-6675 2575) $PN 2
J 0
(-6713 2587);
DISPLAY 0.617021 (-6713 2587);
PAINT WHITE (-6713 2587);
FORCEPROP 2 LAST NO_XNET_CONNECTION 1
J 0
(-6825 2775);
PAINT MONO (-6825 2775);
FORCEPROP 1 LAST PART_NUMBER G21796-066
J 0
(-6825 2675);
DISPLAY 0.617021 (-6825 2675);
PAINT BLUE (-6825 2675);
FORCEPROP 2 LAST SEC 1
J 0
(-6825 2775);
DISPLAY 0.680851 (-6825 2775);
PAINT MONO (-6825 2775);
DISPLAY INVISIBLE (-6825 2775);
FORCEPROP 2 LAST CDS_LOCATION R1D4
J 0
(-6825 2625);
DISPLAY 0.617021 (-6825 2625);
PAINT AQUA (-6825 2625);
DISPLAY INVISIBLE (-6825 2625);
FORCEPROP 1 LAST PATH I79
J 0
(-6825 2725);
DISPLAY 0.978723 (-6825 2725);
PAINT WHITE (-6825 2725);
DISPLAY INVISIBLE (-6825 2725);
FORCEPROP 2 LAST ROOM PVCCIN_CPU1_VR
J 0
(-6825 2725);
DISPLAY 1.021277 (-6825 2725);
PAINT WHITE (-6825 2725);
DISPLAY INVISIBLE (-6825 2725);
FORCEPROP 2 LAST CDS_LIB mstr_discrete
J 0
(-6775 2575);
PAINT MONO (-6775 2575);
DISPLAY INVISIBLE (-6775 2575);
FORCEPROP 2 LAST SEC_TYPE 0402
J 0
(-6825 2775);
DISPLAY 1.021277 (-6825 2775);
PAINT ORANGE (-6825 2775);
DISPLAY INVISIBLE (-6825 2775);
FORCEADD OFFPAGE..2
(-1150 3025);
FORCEPROP 2 LAST $XR0 95 
J 0
(-961 3025);
DISPLAY 0.638298 (-961 3025);
PAINT MONO (-961 3025);
FORCEPROP 2 LAST $XR1 120 
J 0
(-871 3025);
DISPLAY 0.638298 (-871 3025);
PAINT MONO (-871 3025);
FORCEPROP 2 LAST $XR2 145 
J 0
(-751 3025);
DISPLAY 0.638298 (-751 3025);
PAINT MONO (-751 3025);
FORCEPROP 2 LAST CDS_LIB mstr_standard
J 0
(-1150 3025);
PAINT ORANGE (-1150 3025);
DISPLAY INVISIBLE (-1150 3025);
FORCEPROP 2 LAST ROOM PVCCIN_CPU1_VR
J 0
(-1575 3100);
DISPLAY 1.361702 (-1575 3100);
PAINT WHITE (-1575 3100);
DISPLAY INVISIBLE (-1575 3100);
FORCEPROP 2 LAST PATH I8
J 0
(-975 3100);
DISPLAY 1.021277 (-975 3100);
PAINT ORANGE (-975 3100);
DISPLAY INVISIBLE (-975 3100);
FORCEPROP 1 LAST OFFPAGE TRUE
J 0
(-825 2900);
DISPLAY 1.170213 (-825 2900);
PAINT GREEN (-825 2900);
DISPLAY INVISIBLE (-825 2900);
FORCEPROP 1 LAST COMMENT_BODY TRUE
J 0
(-1195 2930);
DISPLAY 1.170213 (-1195 2930);
PAINT PEACH (-1195 2930);
DISPLAY INVISIBLE (-1195 2930);
FORCEADD OFFPAGE..1
(-7500 3900);
FORCEPROP 2 LAST $XR0 55 
J 0
(-7721 3900);
DISPLAY 0.638298 (-7721 3900);
PAINT MONO (-7721 3900);
FORCEPROP 2 LAST $XR1 193 
J 0
(-7841 3900);
DISPLAY 0.638298 (-7841 3900);
PAINT MONO (-7841 3900);
FORCEPROP 2 LAST $XR2 213 
J 0
(-7961 3900);
DISPLAY 0.638298 (-7961 3900);
PAINT MONO (-7961 3900);
FORCEPROP 2 LAST ROOM PVCCIN_CPU1_VR
J 0
(-8050 3975);
DISPLAY 1.361702 (-8050 3975);
PAINT WHITE (-8050 3975);
DISPLAY INVISIBLE (-8050 3975);
FORCEPROP 2 LAST PATH I80
J 0
(-7450 3975);
DISPLAY 1.021277 (-7450 3975);
PAINT ORANGE (-7450 3975);
DISPLAY INVISIBLE (-7450 3975);
FORCEPROP 2 LAST CDS_LIB mstr_standard
J 0
(-7500 3900);
PAINT ORANGE (-7500 3900);
DISPLAY INVISIBLE (-7500 3900);
FORCEPROP 1 LAST OFFPAGE TRUE
J 0
(-7175 3775);
DISPLAY 1.170213 (-7175 3775);
PAINT GREEN (-7175 3775);
DISPLAY INVISIBLE (-7175 3775);
FORCEPROP 1 LAST COMMENT_BODY TRUE
J 0
(-7375 3800);
DISPLAY 1.170213 (-7375 3800);
PAINT PEACH (-7375 3800);
DISPLAY INVISIBLE (-7375 3800);
FORCEADD OFFPAGE..1
(-7500 3225);
FORCEPROP 2 LAST $XR0 207 
J 0
(-7752 3225);
DISPLAY 0.638298 (-7752 3225);
PAINT MONO (-7752 3225);
FORCEPROP 2 LAST PATH I81
J 0
(-7750 3275);
DISPLAY 1.021277 (-7750 3275);
PAINT ORANGE (-7750 3275);
DISPLAY INVISIBLE (-7750 3275);
FORCEPROP 2 LAST ROOM PVCCIN_CPU1_VR
J 0
(-8050 3300);
DISPLAY 1.361702 (-8050 3300);
PAINT WHITE (-8050 3300);
DISPLAY INVISIBLE (-8050 3300);
FORCEPROP 2 LAST CDS_LIB mstr_standard
J 0
(-7500 3225);
PAINT ORANGE (-7500 3225);
DISPLAY INVISIBLE (-7500 3225);
FORCEPROP 1 LAST OFFPAGE TRUE
J 0
(-7175 3100);
DISPLAY 1.170213 (-7175 3100);
PAINT GREEN (-7175 3100);
DISPLAY INVISIBLE (-7175 3100);
FORCEPROP 1 LAST COMMENT_BODY TRUE
J 0
(-7375 3125);
DISPLAY 1.170213 (-7375 3125);
PAINT PEACH (-7375 3125);
DISPLAY INVISIBLE (-7375 3125);
FORCEADD OFFPAGE..1
(-7500 3175);
FORCEPROP 2 LAST $XR0 207 
J 0
(-7752 3175);
DISPLAY 0.638298 (-7752 3175);
PAINT MONO (-7752 3175);
FORCEPROP 2 LAST PATH I82
J 0
(-7750 3225);
DISPLAY 1.021277 (-7750 3225);
PAINT ORANGE (-7750 3225);
DISPLAY INVISIBLE (-7750 3225);
FORCEPROP 2 LAST ROOM PVCCIN_CPU1_VR
J 0
(-8050 3250);
DISPLAY 1.361702 (-8050 3250);
PAINT WHITE (-8050 3250);
DISPLAY INVISIBLE (-8050 3250);
FORCEPROP 2 LAST CDS_LIB mstr_standard
J 0
(-7500 3175);
PAINT ORANGE (-7500 3175);
DISPLAY INVISIBLE (-7500 3175);
FORCEPROP 1 LAST OFFPAGE TRUE
J 0
(-7175 3050);
DISPLAY 1.170213 (-7175 3050);
PAINT GREEN (-7175 3050);
DISPLAY INVISIBLE (-7175 3050);
FORCEPROP 1 LAST COMMENT_BODY TRUE
J 0
(-7375 3075);
DISPLAY 1.170213 (-7375 3075);
PAINT PEACH (-7375 3075);
DISPLAY INVISIBLE (-7375 3075);
FORCEADD OFFPAGE..1
(-7500 3125);
FORCEPROP 2 LAST $XR0 208 
J 0
(-7752 3125);
DISPLAY 0.638298 (-7752 3125);
PAINT MONO (-7752 3125);
FORCEPROP 2 LAST PATH I83
J 0
(-7750 3175);
DISPLAY 1.021277 (-7750 3175);
PAINT ORANGE (-7750 3175);
DISPLAY INVISIBLE (-7750 3175);
FORCEPROP 2 LAST ROOM PVCCIN_CPU1_VR
J 0
(-8050 3200);
DISPLAY 1.361702 (-8050 3200);
PAINT WHITE (-8050 3200);
DISPLAY INVISIBLE (-8050 3200);
FORCEPROP 2 LAST CDS_LIB mstr_standard
J 0
(-7500 3125);
PAINT ORANGE (-7500 3125);
DISPLAY INVISIBLE (-7500 3125);
FORCEPROP 1 LAST OFFPAGE TRUE
J 0
(-7175 3000);
DISPLAY 1.170213 (-7175 3000);
PAINT GREEN (-7175 3000);
DISPLAY INVISIBLE (-7175 3000);
FORCEPROP 1 LAST COMMENT_BODY TRUE
J 0
(-7375 3025);
DISPLAY 1.170213 (-7375 3025);
PAINT PEACH (-7375 3025);
DISPLAY INVISIBLE (-7375 3025);
FORCEADD OFFPAGE..1
(-7500 2925);
FORCEPROP 2 LAST $XR0 207 
J 0
(-7752 2925);
DISPLAY 0.638298 (-7752 2925);
PAINT MONO (-7752 2925);
FORCEPROP 2 LAST PATH I84
J 0
(-7750 2975);
DISPLAY 1.021277 (-7750 2975);
PAINT ORANGE (-7750 2975);
DISPLAY INVISIBLE (-7750 2975);
FORCEPROP 2 LAST ROOM PVCCIN_CPU1_VR
J 0
(-8050 3000);
DISPLAY 1.361702 (-8050 3000);
PAINT WHITE (-8050 3000);
DISPLAY INVISIBLE (-8050 3000);
FORCEPROP 2 LAST CDS_LIB mstr_standard
J 0
(-7500 2925);
PAINT ORANGE (-7500 2925);
DISPLAY INVISIBLE (-7500 2925);
FORCEPROP 1 LAST OFFPAGE TRUE
J 0
(-7175 2800);
DISPLAY 1.170213 (-7175 2800);
PAINT GREEN (-7175 2800);
DISPLAY INVISIBLE (-7175 2800);
FORCEPROP 1 LAST COMMENT_BODY TRUE
J 0
(-7375 2825);
DISPLAY 1.170213 (-7375 2825);
PAINT PEACH (-7375 2825);
DISPLAY INVISIBLE (-7375 2825);
FORCEADD OFFPAGE..1
(-7500 3025);
FORCEPROP 2 LAST $XR0 209 
J 0
(-7752 3025);
DISPLAY 0.638298 (-7752 3025);
PAINT MONO (-7752 3025);
FORCEPROP 2 LAST CDS_LIB mstr_standard
J 0
(-7500 3025);
PAINT ORANGE (-7500 3025);
DISPLAY INVISIBLE (-7500 3025);
FORCEPROP 2 LAST ROOM PVCCIN_CPU1_VR
J 0
(-8050 3100);
DISPLAY 1.361702 (-8050 3100);
PAINT WHITE (-8050 3100);
DISPLAY INVISIBLE (-8050 3100);
FORCEPROP 2 LAST PATH I85
J 0
(-7450 3100);
DISPLAY 1.021277 (-7450 3100);
PAINT ORANGE (-7450 3100);
DISPLAY INVISIBLE (-7450 3100);
FORCEPROP 1 LAST OFFPAGE TRUE
J 0
(-7175 2900);
DISPLAY 1.170213 (-7175 2900);
PAINT GREEN (-7175 2900);
DISPLAY INVISIBLE (-7175 2900);
FORCEPROP 1 LAST COMMENT_BODY TRUE
J 0
(-7375 2925);
DISPLAY 1.170213 (-7375 2925);
PAINT PEACH (-7375 2925);
DISPLAY INVISIBLE (-7375 2925);
FORCEADD OFFPAGE..1
(-7500 3075);
FORCEPROP 2 LAST $XR0 208 
J 0
(-7752 3075);
DISPLAY 0.638298 (-7752 3075);
PAINT MONO (-7752 3075);
FORCEPROP 2 LAST PATH I86
J 0
(-7750 3125);
DISPLAY 1.021277 (-7750 3125);
PAINT ORANGE (-7750 3125);
DISPLAY INVISIBLE (-7750 3125);
FORCEPROP 2 LAST ROOM PVCCIN_CPU1_VR
J 0
(-8050 3150);
DISPLAY 1.361702 (-8050 3150);
PAINT WHITE (-8050 3150);
DISPLAY INVISIBLE (-8050 3150);
FORCEPROP 2 LAST CDS_LIB mstr_standard
J 0
(-7500 3075);
PAINT ORANGE (-7500 3075);
DISPLAY INVISIBLE (-7500 3075);
FORCEPROP 1 LAST OFFPAGE TRUE
J 0
(-7175 2950);
DISPLAY 1.170213 (-7175 2950);
PAINT GREEN (-7175 2950);
DISPLAY INVISIBLE (-7175 2950);
FORCEPROP 1 LAST COMMENT_BODY TRUE
J 0
(-7375 2975);
DISPLAY 1.170213 (-7375 2975);
PAINT PEACH (-7375 2975);
DISPLAY INVISIBLE (-7375 2975);
FORCEADD OFFPAGE..1
(-7500 2875);
FORCEPROP 2 LAST $XR0 207 
J 0
(-7752 2875);
DISPLAY 0.638298 (-7752 2875);
PAINT MONO (-7752 2875);
FORCEPROP 2 LAST PATH I87
J 0
(-7750 2925);
DISPLAY 1.021277 (-7750 2925);
PAINT ORANGE (-7750 2925);
DISPLAY INVISIBLE (-7750 2925);
FORCEPROP 2 LAST ROOM PVCCIN_CPU1_VR
J 0
(-8050 2950);
DISPLAY 1.361702 (-8050 2950);
PAINT WHITE (-8050 2950);
DISPLAY INVISIBLE (-8050 2950);
FORCEPROP 2 LAST CDS_LIB mstr_standard
J 0
(-7500 2875);
PAINT ORANGE (-7500 2875);
DISPLAY INVISIBLE (-7500 2875);
FORCEPROP 1 LAST OFFPAGE TRUE
J 0
(-7175 2750);
DISPLAY 1.170213 (-7175 2750);
PAINT GREEN (-7175 2750);
DISPLAY INVISIBLE (-7175 2750);
FORCEPROP 1 LAST COMMENT_BODY TRUE
J 0
(-7375 2775);
DISPLAY 1.170213 (-7375 2775);
PAINT PEACH (-7375 2775);
DISPLAY INVISIBLE (-7375 2775);
FORCEADD OFFPAGE..1
(-7500 2825);
FORCEPROP 2 LAST $XR0 208 
J 0
(-7752 2825);
DISPLAY 0.638298 (-7752 2825);
PAINT MONO (-7752 2825);
FORCEPROP 2 LAST PATH I88
J 0
(-7750 2875);
DISPLAY 1.021277 (-7750 2875);
PAINT ORANGE (-7750 2875);
DISPLAY INVISIBLE (-7750 2875);
FORCEPROP 2 LAST ROOM PVCCIN_CPU1_VR
J 0
(-8050 2900);
DISPLAY 1.361702 (-8050 2900);
PAINT WHITE (-8050 2900);
DISPLAY INVISIBLE (-8050 2900);
FORCEPROP 2 LAST CDS_LIB mstr_standard
J 0
(-7500 2825);
PAINT ORANGE (-7500 2825);
DISPLAY INVISIBLE (-7500 2825);
FORCEPROP 1 LAST OFFPAGE TRUE
J 0
(-7175 2700);
DISPLAY 0.936170 (-7175 2700);
PAINT GREEN (-7175 2700);
DISPLAY INVISIBLE (-7175 2700);
FORCEPROP 1 LAST COMMENT_BODY TRUE
J 0
(-7375 2725);
DISPLAY 1.170213 (-7375 2725);
PAINT PEACH (-7375 2725);
DISPLAY INVISIBLE (-7375 2725);
FORCEADD OFFPAGE..1
(-7500 2775);
FORCEPROP 2 LAST $XR0 208 
J 0
(-7752 2775);
DISPLAY 0.638298 (-7752 2775);
PAINT MONO (-7752 2775);
FORCEPROP 2 LAST PATH I89
J 0
(-7750 2825);
DISPLAY 1.021277 (-7750 2825);
PAINT ORANGE (-7750 2825);
DISPLAY INVISIBLE (-7750 2825);
FORCEPROP 2 LAST ROOM PVCCIN_CPU1_VR
J 0
(-8050 2850);
DISPLAY 1.361702 (-8050 2850);
PAINT WHITE (-8050 2850);
DISPLAY INVISIBLE (-8050 2850);
FORCEPROP 2 LAST CDS_LIB mstr_standard
J 0
(-7500 2775);
PAINT ORANGE (-7500 2775);
DISPLAY INVISIBLE (-7500 2775);
FORCEPROP 1 LAST OFFPAGE TRUE
J 0
(-7175 2650);
DISPLAY 1.170213 (-7175 2650);
PAINT GREEN (-7175 2650);
DISPLAY INVISIBLE (-7175 2650);
FORCEPROP 1 LAST COMMENT_BODY TRUE
J 0
(-7375 2675);
DISPLAY 1.170213 (-7375 2675);
PAINT PEACH (-7375 2675);
DISPLAY INVISIBLE (-7375 2675);
FORCEADD OFFPAGE..2
(-1150 2925);
FORCEPROP 2 LAST $XR0 193 
J 0
(-961 2925);
DISPLAY 0.638298 (-961 2925);
PAINT MONO (-961 2925);
FORCEPROP 2 LAST $XR1 213 
J 0
(-841 2925);
DISPLAY 0.638298 (-841 2925);
PAINT MONO (-841 2925);
FORCEPROP 2 LAST $XR2 55 
J 0
(-721 2925);
DISPLAY 0.638298 (-721 2925);
PAINT MONO (-721 2925);
FORCEPROP 2 LAST ROOM PVCCIN_CPU1_VR
J 0
(-1575 3000);
DISPLAY 1.361702 (-1575 3000);
PAINT WHITE (-1575 3000);
DISPLAY INVISIBLE (-1575 3000);
FORCEPROP 2 LAST CDS_LIB mstr_standard
J 0
(-1150 2925);
PAINT ORANGE (-1150 2925);
DISPLAY INVISIBLE (-1150 2925);
FORCEPROP 2 LAST PATH I9
J 0
(-975 3000);
DISPLAY 1.021277 (-975 3000);
PAINT ORANGE (-975 3000);
DISPLAY INVISIBLE (-975 3000);
FORCEPROP 1 LAST OFFPAGE TRUE
J 0
(-825 2800);
DISPLAY 1.170213 (-825 2800);
PAINT GREEN (-825 2800);
DISPLAY INVISIBLE (-825 2800);
FORCEPROP 1 LAST COMMENT_BODY TRUE
J 0
(-1195 2830);
DISPLAY 1.170213 (-1195 2830);
PAINT PEACH (-1195 2830);
DISPLAY INVISIBLE (-1195 2830);
FORCEADD OFFPAGE..1
(-7500 2725);
FORCEPROP 2 LAST $XR0 209 
J 0
(-7752 2725);
DISPLAY 0.638298 (-7752 2725);
PAINT MONO (-7752 2725);
FORCEPROP 2 LAST ROOM PVCCIN_CPU1_VR
J 0
(-8050 2800);
DISPLAY 1.361702 (-8050 2800);
PAINT WHITE (-8050 2800);
DISPLAY INVISIBLE (-8050 2800);
FORCEPROP 2 LAST CDS_LIB mstr_standard
J 0
(-7500 2725);
PAINT ORANGE (-7500 2725);
DISPLAY INVISIBLE (-7500 2725);
FORCEPROP 2 LAST PATH I90
J 0
(-7450 2800);
DISPLAY 1.021277 (-7450 2800);
PAINT ORANGE (-7450 2800);
DISPLAY INVISIBLE (-7450 2800);
FORCEPROP 1 LAST OFFPAGE TRUE
J 0
(-7175 2600);
DISPLAY 1.170213 (-7175 2600);
PAINT GREEN (-7175 2600);
DISPLAY INVISIBLE (-7175 2600);
FORCEPROP 1 LAST COMMENT_BODY TRUE
J 0
(-7375 2625);
DISPLAY 1.170213 (-7375 2625);
PAINT PEACH (-7375 2625);
DISPLAY INVISIBLE (-7375 2625);
FORCEADD OFFPAGE..1
(-7500 2575);
FORCEPROP 2 LAST $XR0 209 
J 0
(-7752 2575);
DISPLAY 0.638298 (-7752 2575);
PAINT MONO (-7752 2575);
FORCEPROP 2 LAST PATH I91
J 0
(-7700 2625);
DISPLAY 1.021277 (-7700 2625);
PAINT ORANGE (-7700 2625);
DISPLAY INVISIBLE (-7700 2625);
FORCEPROP 2 LAST ROOM PVCCIN_CPU1_VR
J 0
(-8050 2650);
DISPLAY 1.361702 (-8050 2650);
PAINT WHITE (-8050 2650);
DISPLAY INVISIBLE (-8050 2650);
FORCEPROP 2 LAST CDS_LIB mstr_standard
J 0
(-7500 2575);
PAINT ORANGE (-7500 2575);
DISPLAY INVISIBLE (-7500 2575);
FORCEPROP 1 LAST OFFPAGE TRUE
J 0
(-7175 2450);
DISPLAY 1.170213 (-7175 2450);
PAINT GREEN (-7175 2450);
DISPLAY INVISIBLE (-7175 2450);
FORCEPROP 1 LAST COMMENT_BODY TRUE
J 0
(-7375 2475);
DISPLAY 1.170213 (-7375 2475);
PAINT PEACH (-7375 2475);
DISPLAY INVISIBLE (-7375 2475);
FORCEADD OFFPAGE..1
(-7500 2250);
FORCEPROP 2 LAST $XR0 209 
J 0
(-7752 2250);
DISPLAY 0.638298 (-7752 2250);
PAINT MONO (-7752 2250);
FORCEPROP 2 LAST PATH I92
J 0
(-7700 2300);
DISPLAY 1.021277 (-7700 2300);
PAINT ORANGE (-7700 2300);
DISPLAY INVISIBLE (-7700 2300);
FORCEPROP 2 LAST ROOM PVCCIN_CPU1_VR
J 0
(-8050 2325);
DISPLAY 1.361702 (-8050 2325);
PAINT WHITE (-8050 2325);
DISPLAY INVISIBLE (-8050 2325);
FORCEPROP 2 LAST CDS_LIB mstr_standard
J 0
(-7500 2250);
PAINT ORANGE (-7500 2250);
DISPLAY INVISIBLE (-7500 2250);
FORCEPROP 1 LAST OFFPAGE TRUE
J 0
(-7175 2125);
DISPLAY 1.170213 (-7175 2125);
PAINT GREEN (-7175 2125);
DISPLAY INVISIBLE (-7175 2125);
FORCEPROP 1 LAST COMMENT_BODY TRUE
J 0
(-7375 2150);
DISPLAY 1.170213 (-7375 2150);
PAINT PEACH (-7375 2150);
DISPLAY INVISIBLE (-7375 2150);
FORCEADD OFFPAGE..1
(-7500 2075);
FORCEPROP 2 LAST $XR0 210 
J 0
(-7752 2075);
DISPLAY 0.638298 (-7752 2075);
PAINT MONO (-7752 2075);
FORCEPROP 2 LAST ROOM PVCCIN_CPU1_VR
J 0
(-8050 2150);
DISPLAY 1.361702 (-8050 2150);
PAINT WHITE (-8050 2150);
DISPLAY INVISIBLE (-8050 2150);
FORCEPROP 2 LAST CDS_LIB mstr_standard
J 0
(-7500 2075);
PAINT ORANGE (-7500 2075);
DISPLAY INVISIBLE (-7500 2075);
FORCEPROP 2 LAST PATH I94
J 0
(-7450 2150);
DISPLAY 1.021277 (-7450 2150);
PAINT ORANGE (-7450 2150);
DISPLAY INVISIBLE (-7450 2150);
FORCEPROP 1 LAST OFFPAGE TRUE
J 0
(-7175 1950);
DISPLAY 1.170213 (-7175 1950);
PAINT GREEN (-7175 1950);
DISPLAY INVISIBLE (-7175 1950);
FORCEPROP 1 LAST COMMENT_BODY TRUE
J 0
(-7375 1975);
DISPLAY 1.170213 (-7375 1975);
PAINT PEACH (-7375 1975);
DISPLAY INVISIBLE (-7375 1975);
FORCEADD OFFPAGE..1
(-7500 1825);
FORCEPROP 2 LAST $XR0 191 
J 0
(-7752 1825);
DISPLAY 0.638298 (-7752 1825);
PAINT MONO (-7752 1825);
FORCEPROP 2 LAST ROOM PVCCIN_CPU1_VR
J 0
(-8050 1900);
DISPLAY 1.361702 (-8050 1900);
PAINT WHITE (-8050 1900);
DISPLAY INVISIBLE (-8050 1900);
FORCEPROP 2 LAST CDS_LIB mstr_standard
J 0
(-7500 1825);
PAINT ORANGE (-7500 1825);
DISPLAY INVISIBLE (-7500 1825);
FORCEPROP 2 LAST PATH I95
J 0
(-7450 1900);
DISPLAY 1.021277 (-7450 1900);
PAINT ORANGE (-7450 1900);
DISPLAY INVISIBLE (-7450 1900);
FORCEPROP 1 LAST OFFPAGE TRUE
J 0
(-7175 1700);
DISPLAY 1.170213 (-7175 1700);
PAINT GREEN (-7175 1700);
DISPLAY INVISIBLE (-7175 1700);
FORCEPROP 1 LAST COMMENT_BODY TRUE
J 0
(-7375 1725);
DISPLAY 1.170213 (-7375 1725);
PAINT PEACH (-7375 1725);
DISPLAY INVISIBLE (-7375 1725);
FORCEADD OFFPAGE..1
(-7500 1875);
FORCEPROP 2 LAST $XR0 207 
J 0
(-7752 1875);
DISPLAY 0.638298 (-7752 1875);
PAINT MONO (-7752 1875);
FORCEPROP 2 LAST $XR1 208 
J 0
(-7872 1875);
DISPLAY 0.638298 (-7872 1875);
PAINT MONO (-7872 1875);
FORCEPROP 2 LAST $XR2 209 
J 0
(-7992 1875);
DISPLAY 0.638298 (-7992 1875);
PAINT MONO (-7992 1875);
FORCEPROP 2 LAST PATH I96
J 0
(-7750 1925);
DISPLAY 1.021277 (-7750 1925);
PAINT ORANGE (-7750 1925);
DISPLAY INVISIBLE (-7750 1925);
FORCEPROP 2 LAST ROOM PVCCIN_CPU1_VR
J 0
(-8050 1950);
DISPLAY 1.361702 (-8050 1950);
PAINT WHITE (-8050 1950);
DISPLAY INVISIBLE (-8050 1950);
FORCEPROP 2 LAST CDS_LIB mstr_standard
J 0
(-7500 1875);
PAINT ORANGE (-7500 1875);
DISPLAY INVISIBLE (-7500 1875);
FORCEPROP 1 LAST OFFPAGE TRUE
J 0
(-7175 1750);
DISPLAY 1.170213 (-7175 1750);
PAINT GREEN (-7175 1750);
DISPLAY INVISIBLE (-7175 1750);
FORCEPROP 1 LAST COMMENT_BODY TRUE
J 0
(-7375 1775);
DISPLAY 1.170213 (-7375 1775);
PAINT PEACH (-7375 1775);
DISPLAY INVISIBLE (-7375 1775);
FORCEADD OFFPAGE..1
(-7500 1925);
FORCEPROP 2 LAST $XR0 210 
J 0
(-7752 1925);
DISPLAY 0.638298 (-7752 1925);
PAINT MONO (-7752 1925);
FORCEPROP 2 LAST PATH I97
J 0
(-7450 2000);
DISPLAY 1.021277 (-7450 2000);
PAINT ORANGE (-7450 2000);
DISPLAY INVISIBLE (-7450 2000);
FORCEPROP 2 LAST CDS_LIB mstr_standard
J 0
(-7500 1925);
PAINT ORANGE (-7500 1925);
DISPLAY INVISIBLE (-7500 1925);
FORCEPROP 2 LAST ROOM PVCCIN_CPU1_VR
J 0
(-8050 2000);
DISPLAY 1.361702 (-8050 2000);
PAINT WHITE (-8050 2000);
DISPLAY INVISIBLE (-8050 2000);
FORCEPROP 1 LAST OFFPAGE TRUE
J 0
(-7175 1800);
DISPLAY 1.170213 (-7175 1800);
PAINT GREEN (-7175 1800);
DISPLAY INVISIBLE (-7175 1800);
FORCEPROP 1 LAST COMMENT_BODY TRUE
J 0
(-7375 1825);
DISPLAY 1.170213 (-7375 1825);
PAINT PEACH (-7375 1825);
DISPLAY INVISIBLE (-7375 1825);
FORCEADD OFFPAGE..1
(-7500 1575);
FORCEPROP 2 LAST $XR0 210 
J 0
(-7752 1575);
DISPLAY 0.638298 (-7752 1575);
PAINT MONO (-7752 1575);
FORCEPROP 2 LAST ROOM PVCCIN_CPU1_VR
J 0
(-8050 1650);
DISPLAY 1.361702 (-8050 1650);
PAINT WHITE (-8050 1650);
DISPLAY INVISIBLE (-8050 1650);
FORCEPROP 2 LAST CDS_LIB mstr_standard
J 0
(-7500 1575);
PAINT ORANGE (-7500 1575);
DISPLAY INVISIBLE (-7500 1575);
FORCEPROP 2 LAST PATH I98
J 0
(-7450 1650);
DISPLAY 1.021277 (-7450 1650);
PAINT ORANGE (-7450 1650);
DISPLAY INVISIBLE (-7450 1650);
FORCEPROP 1 LAST OFFPAGE TRUE
J 0
(-7175 1450);
DISPLAY 1.170213 (-7175 1450);
PAINT GREEN (-7175 1450);
DISPLAY INVISIBLE (-7175 1450);
FORCEPROP 1 LAST COMMENT_BODY TRUE
J 0
(-7375 1475);
DISPLAY 1.170213 (-7375 1475);
PAINT PEACH (-7375 1475);
DISPLAY INVISIBLE (-7375 1475);
FORCEADD OFFPAGE..1
(-7500 1725);
FORCEPROP 2 LAST $XR0 206 
J 0
(-7752 1725);
DISPLAY 0.638298 (-7752 1725);
PAINT MONO (-7752 1725);
FORCEPROP 2 LAST PATH I99
J 0
(-7750 1775);
DISPLAY 1.021277 (-7750 1775);
PAINT ORANGE (-7750 1775);
DISPLAY INVISIBLE (-7750 1775);
FORCEPROP 2 LAST ROOM PVCCIN_CPU1_VR
J 0
(-8050 1800);
DISPLAY 1.361702 (-8050 1800);
PAINT WHITE (-8050 1800);
DISPLAY INVISIBLE (-8050 1800);
FORCEPROP 2 LAST CDS_LIB mstr_standard
J 0
(-7500 1725);
PAINT ORANGE (-7500 1725);
DISPLAY INVISIBLE (-7500 1725);
FORCEPROP 1 LAST OFFPAGE TRUE
J 0
(-7175 1600);
DISPLAY 1.170213 (-7175 1600);
PAINT GREEN (-7175 1600);
DISPLAY INVISIBLE (-7175 1600);
FORCEPROP 1 LAST COMMENT_BODY TRUE
J 0
(-7375 1625);
DISPLAY 1.170213 (-7375 1625);
PAINT PEACH (-7375 1625);
DISPLAY INVISIBLE (-7375 1625);
FORCEADD DESIGN_NOTE..1
(-925 4750);
FORCEPROP 0 LAST L1 SVID ADDRESS 0X0 / 0X1
J 0
(-1119 4621);
PAINT VIOLET (-1119 4621);
FORCEPROP 2 LAST ROOM PVCCIN_CPU1_VR
J 0
(-1125 4700);
PAINT WHITE (-1125 4700);
DISPLAY INVISIBLE (-1125 4700);
FORCEPROP 2 LAST BOM_COST SM_CONTROLLER
J 0
(-1125 4700);
PAINT WHITE (-1125 4700);
DISPLAY INVISIBLE (-1125 4700);
FORCEPROP 2 LAST CDS_LIB mstr_symbols
J 0
(-925 4750);
PAINT WHITE (-925 4750);
DISPLAY INVISIBLE (-925 4750);
FORCEPROP 1 LAST COMMENT_BODY TRUE
J 0
(-900 4850);
DISPLAY 1.319149 (-900 4850);
PAINT WHITE (-900 4850);
DISPLAY INVISIBLE (-900 4850);
FORCEADD DNS..2
(-2370 4120);
PAINT RED (-2370 4120);
FORCEPROP 2 LAST CDS_LIB mstr_misc
J 0
(-2370 4120);
PAINT ORANGE (-2370 4120);
DISPLAY INVISIBLE (-2370 4120);
FORCEPROP 1 LAST COMMENT_BODY TRUE
R 1
J 0
(-2295 3895);
DISPLAY 0.872340 (-2295 3895);
PAINT GREEN (-2295 3895);
DISPLAY INVISIBLE (-2295 3895);
FORCEADD INTEL_CORP_BPAGE..1
(-100 25);
FORCEPROP 1 LAST CDS_CON_LAST_MODIFIED Tue Dec 01 11:52:22 2015
J 0
(-1525 350);
PAINT ORANGE (-1525 350);
DISPLAY INVISIBLE (-1525 350);
FORCEPROP 1 LAST CUSTOM_TXT_CDS <CURRENT_DESIGN_SHEET> OF <TOTAL_DESIGN_SHEETS>
J 0
(-600 50);
PAINT GREEN (-600 50);
FORCEPROP 1 LAST CUSTOM_TXT_CDS <CON_LAST_MODIFIED>
J 0
(-2025 375);
PAINT GREEN (-2025 375);
FORCEPROP 2 LAST CUSTOM_TXT_CDS <XR_PAGE_TITLE>
J 0
(-7990 5275);
DISPLAY 0.638298 (-7990 5275);
PAINT PINK (-7990 5275);
DISPLAY INVISIBLE (-7990 5275);
FORCEPROP 1 LAST SCH_TITLE VCCIN CPU1 (1 OF 4)
J 0
(-8050 75);
DISPLAY 1.212766 (-8050 75);
PAINT YELLOW (-8050 75);
FORCEPROP 1 LAST SCH_ADDRESS3 Santa Clara, CA 95052-8119
J 0
(-4075 50);
DISPLAY 0.617021 (-4075 50);
PAINT YELLOW (-4075 50);
FORCEPROP 1 LAST SCH_ADDRESS2 P.O. BOX 58119
J 0
(-4075 100);
DISPLAY 0.617021 (-4075 100);
PAINT YELLOW (-4075 100);
FORCEPROP 1 LAST SCH_ADDRESS1 2200 Mission College Blvd.
J 0
(-4075 150);
DISPLAY 0.617021 (-4075 150);
PAINT YELLOW (-4075 150);
FORCEPROP 1 LAST SCH_NUMBER H4694802
J 0
(-1400 175);
DISPLAY 1.212766 (-1400 175);
PAINT YELLOW (-1400 175);
FORCEPROP 1 LAST SCH_DEPT BESD
J 1
(-4550 125);
DISPLAY 1.212766 (-4550 125);
PAINT YELLOW (-4550 125);
FORCEPROP 1 LAST SCH_REV 2.420
J 0
(-350 175);
DISPLAY 0.978723 (-350 175);
PAINT YELLOW (-350 175);
FORCEPROP 2 LAST PAGE_BORDER TRUE
J 0
(-7990 5275);
DISPLAY 0.638298 (-7990 5275);
PAINT PINK (-7990 5275);
DISPLAY INVISIBLE (-7990 5275);
FORCEPROP 2 LAST CDS_LIB mstr_symbols
J 0
(-100 25);
PAINT MONO (-100 25);
DISPLAY INVISIBLE (-100 25);
FORCEPROP 1 LAST COMMENT_BODY TRUE
J 0
(-88 37);
DISPLAY 0.468085 (-88 37);
PAINT PEACH (-88 37);
DISPLAY INVISIBLE (-88 37);
FORCEPROP 2 LAST CDS_XR_PAGE_TITLE CR-206 : @BASEBOARD_FAB2_LIB.BASEBOARD_FAB2(SCH_1):PAGE206
J 0
(-7990 5275);
DISPLAY 0.638298 (-7990 5275);
PAINT PINK (-7990 5275);
DISPLAY INVISIBLE (-7990 5275);
FORCEADD DNS..2
(-2220 3745);
PAINT RED (-2220 3745);
FORCEPROP 2 LAST CDS_LIB mstr_misc
J 0
(-2220 3745);
PAINT ORANGE (-2220 3745);
DISPLAY INVISIBLE (-2220 3745);
FORCEPROP 1 LAST COMMENT_BODY TRUE
R 1
J 0
(-2145 3520);
DISPLAY 0.872340 (-2145 3520);
PAINT GREEN (-2145 3520);
DISPLAY INVISIBLE (-2145 3520);
FORCEADD DESIGN_NOTE..1
(-4175 1350);
FORCEPROP 0 LAST L1 SMBUS ADDRESS: 0XB0
J 0
(-4375 1225);
DISPLAY 1.021277 (-4375 1225);
PAINT WHITE (-4375 1225);
FORCEPROP 2 LAST CDS_LIB mstr_symbols
J 0
(-4175 1350);
PAINT WHITE (-4175 1350);
DISPLAY INVISIBLE (-4175 1350);
FORCEPROP 1 LAST COMMENT_BODY TRUE
J 0
(-4150 1450);
DISPLAY 0.978723 (-4150 1450);
PAINT WHITE (-4150 1450);
DISPLAY INVISIBLE (-4150 1450);
WIRE 16 -1 (-1375 3850)(-1375 4100);
WIRE 16 -1 (-4350 4550)(-4350 4375);
WIRE 16 -1 (-2050 4200)(-2050 4375);
WIRE 16 -1 (-2225 4375)(-2050 4375);
WIRE 16 -1 (-2225 3850)(-2225 4375);
WIRE 16 -1 (-2375 4375)(-2225 4375);
WIRE 16 -1 (-2375 4225)(-2375 4375);
WIRE 16 -1 (-2725 4375)(-2375 4375);
WIRE 16 -1 (-2725 4025)(-2725 4375);
WIRE 16 -1 (-2875 4375)(-2725 4375);
WIRE 16 -1 (-2875 4025)(-2875 4375);
WIRE 16 -1 (-3075 4375)(-2875 4375);
WIRE 16 -1 (-3075 4100)(-3075 4375);
WIRE 16 -1 (-3075 4375)(-3075 4525);
WIRE 16 -1 (-1450 2050)(-1450 1975);
WIRE 16 -1 (-1575 725)(-1575 900);
WIRE 16 -1 (-1975 850)(-1975 900);
WIRE 16 -1 (-3650 3775)(-3650 3825);
WIRE 16 -1 (-4050 3775)(-4050 3825);
WIRE 16 -1 (-3175 1600)(-3175 1875);
WIRE 16 -1 (-3175 1875)(-3375 1875);
WIRE 16 -1 (-4650 4500)(-4650 4700);
WIRE 16 -1 (-4650 4700)(-5225 4700);
WIRE 16 -1 (-5225 4700)(-5650 4700);
WIRE 16 -1 (-5225 4700)(-5225 4825);
WIRE 16 -1 (-5650 4550)(-5650 4700);
WIRE 16 -1 (-6150 4675)(-6150 4825);
WIRE 16 -1 (-6150 4025)(-6150 4125);
WIRE 16 -1 (-4500 625)(-4500 825);
WIRE 16 -1 (-4825 575)(-4825 825);
WIRE 16 -1 (-5925 625)(-5925 1175);
WIRE 16 -1 (-6150 625)(-6150 900);
WIRE 16 -1 (-6425 4025)(-6425 4100);
WIRE 16 -1 (-7675 1350)(-6975 1350);
FORCEPROP 2 LAST SIG_NAME VR_PVCCIN_CPU1_VD12
J 0
(-7615 1365);
DISPLAY 0.617021 (-7615 1365);
PAINT ORANGE (-7615 1365);
WIRE 16 -1 (-7450 2075)(-6450 2075);
FORCEPROP 2 LAST SIG_NAME VSENSE_PVSA_CPU1_P
J 0
(-7465 2090);
DISPLAY 0.617021 (-7465 2090);
PAINT ORANGE (-7465 2090);
WIRE 16 -1 (-7450 2575)(-6875 2575);
FORCEPROP 2 LAST SIG_NAME VSENSE_PVCCIN_CPU1_P
J 0
(-7465 2590);
DISPLAY 0.617021 (-7465 2590);
PAINT ORANGE (-7465 2590);
WIRE 16 -1 (-7450 2725)(-4275 2725);
FORCEPROP 2 LAST SIG_NAME ISENSE_PVCCIN_CPU1_PH5_IMON
J 0
(-7440 2740);
DISPLAY 0.617021 (-7440 2740);
PAINT ORANGE (-7440 2740);
WIRE 16 -1 (-7450 2825)(-4275 2825);
FORCEPROP 2 LAST SIG_NAME ISENSE_PVCCIN_CPU1_PH3_IMON
J 0
(-7440 2840);
DISPLAY 0.617021 (-7440 2840);
PAINT ORANGE (-7440 2840);
WIRE 16 -1 (-7450 2875)(-4275 2875);
FORCEPROP 2 LAST SIG_NAME ISENSE_PVCCIN_CPU1_PH2_IMON
J 0
(-7440 2890);
DISPLAY 0.617021 (-7440 2890);
PAINT ORANGE (-7440 2890);
WIRE 16 -1 (-7450 2925)(-4275 2925);
FORCEPROP 2 LAST SIG_NAME ISENSE_PVCCIN_CPU1_PH1_IMON
J 0
(-7440 2940);
DISPLAY 0.617021 (-7440 2940);
PAINT ORANGE (-7440 2940);
WIRE 16 -1 (-4275 3125)(-6150 3125);
WIRE 16 -1 (-6150 3125)(-6150 3450);
WIRE 16 -1 (-7450 3125)(-6150 3125);
FORCEPROP 2 LAST SIG_NAME VR_PVCCIN_CPU1_AIREF3
J 2
(-7025 3140);
DISPLAY 0.617021 (-7025 3140);
PAINT ORANGE (-7025 3140);
WIRE 16 -1 (-6550 3425)(-6550 3175);
WIRE 16 -1 (-4275 3175)(-6550 3175);
WIRE 16 -1 (-7450 3175)(-6550 3175);
FORCEPROP 2 LAST SIG_NAME VR_PVCCIN_CPU1_AIREF2
J 2
(-7025 3190);
DISPLAY 0.617021 (-7025 3190);
PAINT ORANGE (-7025 3190);
WIRE 16 -1 (-6950 3425)(-6950 3225);
WIRE 16 -1 (-4275 3225)(-6950 3225);
WIRE 16 -1 (-7450 3225)(-6950 3225);
FORCEPROP 2 LAST SIG_NAME VR_PVCCIN_CPU1_AIREF1
J 2
(-7025 3240);
DISPLAY 0.617021 (-7025 3240);
PAINT ORANGE (-7025 3240);
WIRE 16 -1 (-6550 2475)(-6550 2575);
WIRE 16 -1 (-4275 2575)(-6550 2575);
FORCEPROP 2 LAST SIG_NAME VSENSE_PVCCIN_CPU1_AVSP
J 0
(-5740 2590);
DISPLAY 0.617021 (-5740 2590);
PAINT ORANGE (-5740 2590);
FORCEPROP 2 LASTPROP $XRERR UNIQUE?
J 0
(-5980 2590);
DISPLAY 0.638298 (-5980 2590);
PAINT MONO (-5980 2590);
DISPLAY INVISIBLE (-5980 2590);
WIRE 16 -1 (-6675 2575)(-6550 2575);
WIRE 16 -1 (-4275 2525)(-6150 2525);
WIRE 16 -1 (-6150 2525)(-6150 2250);
WIRE 16 -1 (-6150 2250)(-6550 2250);
WIRE 16 -1 (-6550 2275)(-6550 2250);
WIRE 16 -1 (-6550 2250)(-7450 2250);
FORCEPROP 2 LAST SIG_NAME VSENSE_PVCCIN_CPU1_N
J 0
(-7465 2265);
DISPLAY 0.617021 (-7465 2265);
PAINT ORANGE (-7465 2265);
WIRE 16 -1 (-4275 1875)(-5125 1875);
WIRE 16 -1 (-5125 1875)(-5125 1475);
WIRE 16 -1 (-7450 1475)(-5125 1475);
FORCEPROP 2 LAST SIG_NAME ISENSE_PVSA_CPU1_IMON
J 0
(-7440 1490);
DISPLAY 0.617021 (-7440 1490);
PAINT ORANGE (-7440 1490);
WIRE 16 -1 (-5225 1975)(-4275 1975);
WIRE 16 -1 (-5225 1575)(-5225 1975);
WIRE 16 -1 (-5225 1575)(-6150 1575);
WIRE 16 -1 (-6150 1100)(-6150 1575);
WIRE 16 -1 (-7450 1575)(-6150 1575);
FORCEPROP 2 LAST SIG_NAME A_TSENSE_PVSA_CPU1
J 0
(-7440 1590);
DISPLAY 0.617021 (-7440 1590);
PAINT ORANGE (-7440 1590);
WIRE 16 -1 (-4275 1925)(-5175 1925);
WIRE 16 -1 (-5175 1925)(-5175 1525);
WIRE 16 -1 (-5175 1525)(-6675 1525);
WIRE 16 -1 (-6675 1350)(-6675 1525);
WIRE 16 -1 (-7450 1525)(-6675 1525);
FORCEPROP 2 LAST SIG_NAME VR_PVSA_CPU1_BIREF1
J 0
(-7440 1540);
DISPLAY 0.617021 (-7440 1540);
PAINT ORANGE (-7440 1540);
WIRE 16 -1 (-6775 1350)(-6675 1350);
WIRE 16 -1 (-4825 1825)(-4275 1825);
FORCEPROP 0 LAST VOLTAGE 3.3
J 0
(-4550 1875);
DISPLAY 1.021277 (-4550 1875);
PAINT SKYBLUE (-4550 1875);
DISPLAY INVISIBLE (-4550 1875);
WIRE 16 -1 (-4825 1025)(-4825 1825);
FORCEPROP 0 LAST SIG_NAME VR_PVCCIN_CPU1_XADDR1
R 1
J 0
(-4835 1085);
DISPLAY 0.617021 (-4835 1085);
PAINT ORANGE (-4835 1085);
FORCEPROP 2 LASTPROP $XRERR UNIQUE?
J 0
(-5075 1085);
DISPLAY 0.638298 (-5075 1085);
PAINT MONO (-5075 1085);
DISPLAY INVISIBLE (-5075 1085);
WIRE 16 -1 (-4500 1775)(-4275 1775);
FORCEPROP 0 LAST VOLTAGE 3.3
J 0
(-4375 1825);
DISPLAY 1.021277 (-4375 1825);
PAINT SKYBLUE (-4375 1825);
DISPLAY INVISIBLE (-4375 1825);
WIRE 16 -1 (-4500 1025)(-4500 1775);
FORCEPROP 0 LAST SIG_NAME VR_PVCCIN_CPU1_XADDR2
R 1
J 0
(-4510 1085);
DISPLAY 0.617021 (-4510 1085);
PAINT ORANGE (-4510 1085);
FORCEPROP 2 LASTPROP $XRERR UNIQUE?
J 0
(-4750 1085);
DISPLAY 0.638298 (-4750 1085);
PAINT MONO (-4750 1085);
DISPLAY INVISIBLE (-4750 1085);
WIRE 16 -1 (-5300 2275)(-5400 2275);
WIRE 16 -1 (-5400 1825)(-5400 2275);
WIRE 16 -1 (-7450 1825)(-5400 1825);
FORCEPROP 2 LAST SIG_NAME FM_PVCCIN_PVCCSA_CPU1_EN_LVC1
J 0
(-7457 1844);
DISPLAY 0.617021 (-7457 1844);
PAINT ORANGE (-7457 1844);
WIRE 16 -1 (-5275 3750)(-5275 3650);
WIRE 16 -1 (-5725 3750)(-5275 3750);
WIRE 16 -1 (-5725 3650)(-5725 3750);
WIRE 16 -1 (-5725 3750)(-6150 3750);
WIRE 16 -1 (-6150 3650)(-6150 3750);
WIRE 16 -1 (-6550 3750)(-6150 3750);
WIRE 16 -1 (-6550 3625)(-6550 3750);
WIRE 16 -1 (-6950 3750)(-6550 3750);
WIRE 16 -1 (-6950 3625)(-6950 3750);
WIRE 16 -1 (-7450 3750)(-6950 3750);
FORCEPROP 2 LAST SIG_NAME VR_PVCCIN_CPU1_VD12
J 2
(-6975 3765);
DISPLAY 0.617021 (-6975 3765);
PAINT ORANGE (-6975 3765);
WIRE 16 -1 (-5275 3450)(-5275 3025);
WIRE 16 -1 (-4275 3025)(-5275 3025);
WIRE 16 -1 (-7450 3025)(-5275 3025);
FORCEPROP 2 LAST SIG_NAME VR_PVCCIN_CPU1_AIREF5
J 2
(-7025 3040);
DISPLAY 0.617021 (-7025 3040);
PAINT ORANGE (-7025 3040);
WIRE 16 -1 (-4275 3075)(-5725 3075);
WIRE 16 -1 (-5725 3075)(-5725 3450);
WIRE 16 -1 (-7450 3075)(-5725 3075);
FORCEPROP 2 LAST SIG_NAME VR_PVCCIN_CPU1_AIREF4
J 2
(-7025 3090);
DISPLAY 0.617021 (-7025 3090);
PAINT ORANGE (-7025 3090);
WIRE 16 -1 (-5650 2475)(-4275 2475);
WIRE 16 -1 (-5650 2275)(-5650 2475);
FORCEPROP 2 LAST SIG_NAME VSENSE_PVSA_CPU1_BVSP
J 0
(-5690 2490);
DISPLAY 0.617021 (-5690 2490);
PAINT ORANGE (-5690 2490);
FORCEPROP 2 LASTPROP $XRERR UNIQUE?
J 0
(-5930 2490);
DISPLAY 0.638298 (-5930 2490);
PAINT MONO (-5930 2490);
DISPLAY INVISIBLE (-5930 2490);
WIRE 16 -1 (-5650 2175)(-5650 2275);
WIRE 16 -1 (-6075 2275)(-5650 2275);
WIRE 16 -1 (-6075 2075)(-6075 2275);
WIRE 16 -1 (-6250 2075)(-6075 2075);
WIRE 16 -1 (-5350 2225)(-4275 2225);
WIRE 16 -1 (-5350 1725)(-5350 2225);
WIRE 16 -1 (-7450 1725)(-5350 1725);
FORCEPROP 0 LAST VOLTAGE 0.8
J 0
(-7425 1800);
DISPLAY 1.021277 (-7425 1800);
PAINT SKYBLUE (-7425 1800);
DISPLAY INVISIBLE (-7425 1800);
FORCEPROP 2 LAST SIG_NAME VR_PVCCIN_CPU1_AVINSEN
J 0
(-7440 1740);
DISPLAY 0.617021 (-7440 1740);
PAINT ORANGE (-7440 1740);
WIRE 16 -1 (-5300 2175)(-4275 2175);
WIRE 16 -1 (-5300 1675)(-5300 2175);
WIRE 16 -1 (-7450 1675)(-5300 1675);
FORCEPROP 0 LAST VOLTAGE +1.5V
J 0
(-7450 1725);
DISPLAY 1.021277 (-7450 1725);
PAINT SKYBLUE (-7450 1725);
DISPLAY INVISIBLE (-7450 1725);
FORCEPROP 2 LAST SIG_NAME PVCCIN_PVSA_CPU1_IINSEN
J 0
(-7450 1675);
DISPLAY 0.617021 (-7450 1675);
PAINT ORANGE (-7450 1675);
WIRE 16 -1 (-5475 2325)(-4275 2325);
WIRE 16 -1 (-5475 1875)(-5475 2325);
WIRE 16 -1 (-5475 1875)(-5925 1875);
WIRE 16 -1 (-5925 1375)(-5925 1875);
WIRE 16 -1 (-7450 1875)(-5925 1875);
FORCEPROP 0 LAST VOLTAGE 3.6
J 0
(-7450 1950);
DISPLAY 1.021277 (-7450 1950);
PAINT SKYBLUE (-7450 1950);
DISPLAY INVISIBLE (-7450 1950);
FORCEPROP 2 LAST SIG_NAME A_TSENSE_PVCCIN_CPU1
J 0
(-7465 1890);
DISPLAY 0.617021 (-7465 1890);
PAINT ORANGE (-7465 1890);
WIRE 16 -1 (-4275 2425)(-5550 2425);
WIRE 16 -1 (-5550 2425)(-5550 1925);
WIRE 16 -1 (-5550 1925)(-5650 1925);
WIRE 16 -1 (-5650 1975)(-5650 1925);
WIRE 16 -1 (-5650 1925)(-7450 1925);
FORCEPROP 2 LAST SIG_NAME VSENSE_PVSA_CPU1_N
J 0
(-7465 1940);
DISPLAY 0.617021 (-7465 1940);
PAINT ORANGE (-7465 1940);
WIRE 16 -1 (-4850 2975)(-4275 2975);
FORCEPROP 0 LAST SIG_NAME TP_PVCCIN_CPU1_AIREF6
J 0
(-4835 2985);
DISPLAY 0.617021 (-4835 2985);
PAINT ORANGE (-4835 2985);
FORCEPROP 2 LASTPROP $XRERR UNIQUE?
J 0
(-5090 2975);
DISPLAY 0.638298 (-5090 2975);
PAINT MONO (-5090 2975);
DISPLAY INVISIBLE (-5090 2975);
WIRE 16 -1 (-4275 2675)(-4900 2675);
FORCEPROP 0 LAST SIG_NAME TP_PVCCIN_CPU1_AISEN6
J 0
(-4885 2685);
DISPLAY 0.617021 (-4885 2685);
PAINT ORANGE (-4885 2685);
FORCEPROP 2 LASTPROP $XRERR UNIQUE?
J 0
(-5140 2675);
DISPLAY 0.638298 (-5140 2675);
PAINT MONO (-5140 2675);
DISPLAY INVISIBLE (-5140 2675);
WIRE 16 -1 (-5025 2075)(-4275 2075);
FORCEPROP 0 LAST SIG_NAME TP_PVCCIN_CPU1_RESET_N
J 0
(-5010 2085);
DISPLAY 0.617021 (-5010 2085);
PAINT ORANGE (-5010 2085);
FORCEPROP 2 LASTPROP $XRERR UNIQUE?
J 0
(-5265 2075);
DISPLAY 0.638298 (-5265 2075);
PAINT MONO (-5265 2075);
DISPLAY INVISIBLE (-5265 2075);
WIRE 16 -1 (-4500 3900)(-4500 3325);
WIRE 16 -1 (-5275 3900)(-4500 3900);
FORCEPROP 2 LAST SIG_NAME SVID_VCLK_PVCCIN_CPU1
J 0
(-5115 3915);
DISPLAY 0.617021 (-5115 3915);
PAINT ORANGE (-5115 3915);
FORCEPROP 2 LASTPROP $XRERR UNIQUE?
J 0
(-5355 3915);
DISPLAY 0.638298 (-5355 3915);
PAINT MONO (-5355 3915);
DISPLAY INVISIBLE (-5355 3915);
WIRE 16 -1 (-4500 3325)(-4275 3325);
WIRE 16 -1 (-5475 3900)(-5650 3900);
WIRE 16 -1 (-5650 4350)(-5650 3900);
WIRE 16 -1 (-7450 3900)(-5650 3900);
FORCEPROP 2 LAST SIG_NAME SVID_CLK0_CPU1_R
J 0
(-7437 3920);
DISPLAY 0.617021 (-7437 3920);
PAINT ORANGE (-7437 3920);
WIRE 16 -1 (-4650 2275)(-4650 4300);
WIRE 16 -1 (-4650 2275)(-4275 2275);
FORCEPROP 0 LAST VOLTAGE 3.3
J 0
(-4450 2325);
DISPLAY 1.021277 (-4450 2325);
PAINT SKYBLUE (-4450 2325);
DISPLAY INVISIBLE (-4450 2325);
WIRE 16 -1 (-5100 2275)(-4650 2275);
FORCEPROP 2 LAST SIG_NAME VR_PVCCIN_CPU1_VREN
J 0
(-5100 2290);
DISPLAY 0.617021 (-5100 2290);
PAINT ORANGE (-5100 2290);
FORCEPROP 2 LASTPROP $XRERR UNIQUE?
J 0
(-5340 2290);
DISPLAY 0.638298 (-5340 2290);
PAINT MONO (-5340 2290);
DISPLAY INVISIBLE (-5340 2290);
WIRE 16 -1 (-6150 4325)(-6150 4425);
WIRE 16 -1 (-6150 4425)(-6150 4475);
WIRE 16 -1 (-6425 4425)(-6150 4425);
WIRE 16 -1 (-6425 4300)(-6425 4425);
WIRE 16 -1 (-6425 4425)(-7450 4425);
FORCEPROP 2 LAST SIG_NAME VR_PVCCIN_CPU1_AVINSEN
J 0
(-7465 4440);
DISPLAY 0.617021 (-7465 4440);
PAINT ORANGE (-7465 4440);
WIRE 16 -1 (-3650 4025)(-3650 4075);
WIRE 16 -1 (-3650 4075)(-4050 4075);
FORCEPROP 2 LAST SIG_NAME VR_PVCCIN_CPU1_VDD
J 0
(-4115 4090);
DISPLAY 0.617021 (-4115 4090);
PAINT ORANGE (-4115 4090);
FORCEPROP 2 LASTPROP $XRERR UNIQUE?
J 0
(-4355 4090);
DISPLAY 0.638298 (-4355 4090);
PAINT MONO (-4355 4090);
DISPLAY INVISIBLE (-4355 4090);
WIRE 16 -1 (-4050 4025)(-4050 4075);
WIRE 16 -1 (-4050 4075)(-4350 4075);
WIRE 16 -1 (-4350 4175)(-4350 4075);
WIRE 16 -1 (-4350 4075)(-4350 3425);
FORCEPROP 0 LAST VOLTAGE 3.3
J 0
(-4350 3800);
DISPLAY 1.021277 (-4350 3800);
PAINT SKYBLUE (-4350 3800);
DISPLAY INVISIBLE (-4350 3800);
WIRE 16 -1 (-4275 3425)(-4350 3425);
WIRE 16 -1 (-3075 3900)(-3075 3025);
FORCEPROP 0 LAST SIG_NAME IRQ_PVCCIN_CPU1_VRHOT_LVC3_R_N
J 0
(-3300 3035);
DISPLAY 0.617021 (-3300 3035);
PAINT ORANGE (-3300 3035);
FORCEPROP 2 LASTPROP $XRERR UNIQUE?
J 0
(-3540 3035);
DISPLAY 0.638298 (-3540 3035);
PAINT MONO (-3540 3035);
DISPLAY INVISIBLE (-3540 3035);
WIRE 16 -1 (-2525 3025)(-3075 3025);
WIRE 16 -1 (-3375 3025)(-3075 3025);
WIRE 16 -1 (-3375 3125)(-2625 3125);
FORCEPROP 2 LAST SIG_NAME TP_PVCCIN_CPU1_FAULT1_20
J 0
(-3290 3140);
DISPLAY 0.617021 (-3290 3140);
PAINT ORANGE (-3290 3140);
FORCEPROP 2 LASTPROP $XRERR UNIQUE?
J 0
(-2595 3125);
DISPLAY 0.638298 (-2595 3125);
PAINT MONO (-2595 3125);
DISPLAY INVISIBLE (-2595 3125);
WIRE 16 -1 (-3375 2675)(-2725 2675);
FORCEPROP 0 LAST SIG_NAME TP_PVCCIN_CPU1_GP1
J 0
(-3275 2685);
DISPLAY 0.617021 (-3275 2685);
PAINT ORANGE (-3275 2685);
FORCEPROP 2 LASTPROP $XRERR UNIQUE?
J 0
(-2695 2675);
DISPLAY 0.638298 (-2695 2675);
PAINT MONO (-2695 2675);
DISPLAY INVISIBLE (-2695 2675);
WIRE 16 -1 (-2225 2925)(-3375 2925);
FORCEPROP 2 LAST SIG_NAME SVID_VALERT_VCCIN_CPU1
J 0
(-3275 2940);
DISPLAY 0.617021 (-3275 2940);
PAINT ORANGE (-3275 2940);
FORCEPROP 2 LASTPROP $XRERR UNIQUE?
J 0
(-3515 2940);
DISPLAY 0.638298 (-3515 2940);
PAINT MONO (-3515 2940);
DISPLAY INVISIBLE (-3515 2940);
WIRE 16 -1 (-2600 2775)(-3375 2775);
FORCEPROP 0 LAST SIG_NAME SVID_VDIO_PVCCIN_CPU1
J 0
(-3275 2785);
DISPLAY 0.617021 (-3275 2785);
PAINT ORANGE (-3275 2785);
FORCEPROP 2 LASTPROP $XRERR UNIQUE?
J 0
(-3515 2785);
DISPLAY 0.638298 (-3515 2785);
PAINT MONO (-3515 2785);
DISPLAY INVISIBLE (-3515 2785);
WIRE 16 -1 (-3375 2275)(-2725 2275);
FORCEPROP 0 LAST SIG_NAME TP_PVCCIN_CPU1_APWM6
J 0
(-3260 2285);
DISPLAY 0.617021 (-3260 2285);
PAINT ORANGE (-3260 2285);
FORCEPROP 2 LASTPROP $XRERR UNIQUE?
J 0
(-2695 2275);
DISPLAY 0.638298 (-2695 2275);
PAINT MONO (-2695 2275);
DISPLAY INVISIBLE (-2695 2275);
WIRE 16 -1 (-2600 2075)(-3375 2075);
FORCEPROP 2 LAST SIG_NAME SMB_VR_SCL_R1
J 0
(-3240 2090);
DISPLAY 0.617021 (-3240 2090);
PAINT ORANGE (-3240 2090);
FORCEPROP 2 LASTPROP $XRERR UNIQUE?
J 0
(-3480 2090);
DISPLAY 0.638298 (-3480 2090);
PAINT MONO (-3480 2090);
DISPLAY INVISIBLE (-3480 2090);
WIRE 16 -1 (-2600 2075)(-2600 1525);
WIRE 16 -1 (-2600 1525)(-2100 1525);
WIRE 16 -1 (-2525 2175)(-3375 2175);
FORCEPROP 2 LAST SIG_NAME SMB_VR_SDA_R1
J 0
(-3240 2190);
DISPLAY 0.617021 (-3240 2190);
PAINT ORANGE (-3240 2190);
FORCEPROP 2 LASTPROP $XRERR UNIQUE?
J 0
(-3480 2190);
DISPLAY 0.638298 (-3480 2190);
PAINT MONO (-3480 2190);
DISPLAY INVISIBLE (-3480 2190);
WIRE 16 -1 (-2525 1775)(-2525 2175);
WIRE 16 -1 (-2525 1775)(-2100 1775);
WIRE 16 -1 (-2875 2725)(-2875 3825);
WIRE 16 -1 (-2875 2725)(-2275 2725);
WIRE 16 -1 (-3375 2725)(-2875 2725);
FORCEPROP 2 LAST SIG_NAME PWRGD_PVSA_CPU1_R
J 0
(-3275 2740);
DISPLAY 0.617021 (-3275 2740);
PAINT ORANGE (-3275 2740);
FORCEPROP 2 LASTPROP $XRERR UNIQUE?
J 0
(-3515 2740);
DISPLAY 0.638298 (-3515 2740);
PAINT MONO (-3515 2740);
DISPLAY INVISIBLE (-3515 2740);
WIRE 16 -1 (-2375 4025)(-2375 3325);
WIRE 16 -1 (-3375 3325)(-2375 3325);
FORCEPROP 2 LAST SIG_NAME PU_VR_PVCCIN_CPU1_FLT1_SMBALT_N_IMON
J 0
(-3298 3341);
DISPLAY 0.617021 (-3298 3341);
PAINT ORANGE (-3298 3341);
FORCEPROP 2 LASTPROP $XRERR UNIQUE?
J 0
(-3538 3341);
DISPLAY 0.638298 (-3538 3341);
PAINT MONO (-3538 3341);
DISPLAY INVISIBLE (-3538 3341);
WIRE 16 -1 (-2225 3650)(-2225 3175);
WIRE 16 -1 (-3375 3175)(-2225 3175);
FORCEPROP 2 LAST SIG_NAME PU_VR_PVCCIN_CPU1_IMON
J 0
(-3275 3190);
DISPLAY 0.617021 (-3275 3190);
PAINT ORANGE (-3275 3190);
FORCEPROP 2 LASTPROP $XRERR UNIQUE?
J 0
(-3515 3190);
DISPLAY 0.638298 (-3515 3190);
PAINT MONO (-3515 3190);
DISPLAY INVISIBLE (-3515 3190);
WIRE 16 -1 (-1200 3025)(-2325 3025);
FORCEPROP 0 LAST SIG_NAME IRQ_PVCCIN_CPU1_VRHOT_LVC3_N
J 0
(-1975 3035);
DISPLAY 0.617021 (-1975 3035);
PAINT ORANGE (-1975 3035);
WIRE 16 -1 (-3375 2325)(-1200 2325);
FORCEPROP 2 LAST SIG_NAME VR_PVCCIN_CPU1_PWM5
J 0
(-1890 2340);
DISPLAY 0.617021 (-1890 2340);
PAINT ORANGE (-1890 2340);
WIRE 16 -1 (-3375 2425)(-1200 2425);
FORCEPROP 0 LAST VOLTAGE 3.6
J 0
(-1875 2500);
DISPLAY 1.021277 (-1875 2500);
PAINT SKYBLUE (-1875 2500);
DISPLAY INVISIBLE (-1875 2500);
FORCEPROP 2 LAST SIG_NAME VR_PVCCIN_CPU1_PWM3
J 0
(-1890 2440);
DISPLAY 0.617021 (-1890 2440);
PAINT ORANGE (-1890 2440);
WIRE 16 -1 (-3375 2375)(-1200 2375);
FORCEPROP 0 LAST VOLTAGE 3.6
J 0
(-1875 2450);
DISPLAY 1.021277 (-1875 2450);
PAINT SKYBLUE (-1875 2450);
DISPLAY INVISIBLE (-1875 2450);
FORCEPROP 2 LAST SIG_NAME VR_PVCCIN_CPU1_PWM4
J 0
(-1890 2390);
DISPLAY 0.617021 (-1890 2390);
PAINT ORANGE (-1890 2390);
WIRE 16 -1 (-3375 2525)(-1200 2525);
FORCEPROP 0 LAST VOLTAGE 3.6
J 0
(-1875 2600);
DISPLAY 1.021277 (-1875 2600);
PAINT SKYBLUE (-1875 2600);
DISPLAY INVISIBLE (-1875 2600);
FORCEPROP 2 LAST SIG_NAME VR_PVCCIN_CPU1_PWM1
J 0
(-1890 2540);
DISPLAY 0.617021 (-1890 2540);
PAINT ORANGE (-1890 2540);
WIRE 16 -1 (-3375 2475)(-1200 2475);
FORCEPROP 0 LAST VOLTAGE 3.6
J 0
(-1875 2550);
DISPLAY 1.021277 (-1875 2550);
PAINT SKYBLUE (-1875 2550);
DISPLAY INVISIBLE (-1875 2550);
FORCEPROP 2 LAST SIG_NAME VR_PVCCIN_CPU1_PWM2
J 0
(-1890 2490);
DISPLAY 0.617021 (-1890 2490);
PAINT ORANGE (-1890 2490);
WIRE 16 -1 (-3375 2575)(-1200 2575);
FORCEPROP 0 LAST VOLTAGE 3.6
J 0
(-1875 2650);
DISPLAY 1.021277 (-1875 2650);
PAINT SKYBLUE (-1875 2650);
DISPLAY INVISIBLE (-1875 2650);
FORCEPROP 2 LAST SIG_NAME VR_PVSA_CPU1_PWM
J 0
(-1890 2590);
DISPLAY 0.617021 (-1890 2590);
PAINT ORANGE (-1890 2590);
WIRE 16 -1 (-2075 2725)(-1200 2725);
FORCEPROP 2 LAST SIG_NAME PWRGD_PVSA_CPU1
J 0
(-1900 2740);
DISPLAY 0.617021 (-1900 2740);
PAINT ORANGE (-1900 2740);
WIRE 16 -1 (-3375 2825)(-1200 2825);
FORCEPROP 2 LAST SIG_NAME VR_PVCCIN_CPU1_VD12
J 0
(-1900 2840);
DISPLAY 0.617021 (-1900 2840);
PAINT ORANGE (-1900 2840);
WIRE 16 -1 (-1200 3125)(-2050 3125);
FORCEPROP 2 LAST SIG_NAME FM_PVCCIN_CPU1_PWR_IN_ALERT_N
J 0
(-1905 3147);
DISPLAY 0.617021 (-1905 3147);
PAINT ORANGE (-1905 3147);
WIRE 16 -1 (-2050 3275)(-2050 3125);
WIRE 16 -1 (-2050 4000)(-2050 3275);
WIRE 16 -1 (-3375 3275)(-2050 3275);
WIRE 16 -1 (-1900 1525)(-900 1525);
FORCEPROP 2 LAST SIG_NAME SMB_VR_STBY_LVC3_SCL
J 0
(-1565 1540);
DISPLAY 0.617021 (-1565 1540);
PAINT ORANGE (-1565 1540);
WIRE 16 -1 (-1900 1775)(-900 1775);
FORCEPROP 2 LAST SIG_NAME SMB_VR_STBY_LVC3_SDA
J 0
(-1565 1790);
DISPLAY 0.617021 (-1565 1790);
PAINT ORANGE (-1565 1790);
WIRE 16 -1 (-1575 1100)(-1575 1175);
WIRE 16 -1 (-1575 1175)(-1000 1175);
WIRE 16 -1 (-1575 1175)(-1975 1175);
FORCEPROP 2 LAST SIG_NAME VR_PVCCIN_CPU1_VD12
J 0
(-1890 1190);
DISPLAY 0.617021 (-1890 1190);
PAINT ORANGE (-1890 1190);
WIRE 16 -1 (-1975 1100)(-1975 1175);
WIRE 16 -1 (-2025 2925)(-1200 2925);
FORCEPROP 2 LAST SIG_NAME SVID_ALERT0_CPU1_R_N
J 0
(-1900 2935);
DISPLAY 0.617021 (-1900 2935);
PAINT ORANGE (-1900 2935);
WIRE 16 -1 (-1225 2775)(-1375 2775);
WIRE 16 -1 (-1375 2775)(-1375 3650);
WIRE 16 -1 (-2400 2775)(-1375 2775);
FORCEPROP 0 LAST SIG_NAME SVID_DIO0_CPU1_R
J 0
(-1900 2785);
DISPLAY 0.617021 (-1900 2785);
PAINT ORANGE (-1900 2785);
WIRE 16 -1 (-1450 2250)(-1450 3375);
WIRE 16 -1 (-1450 3375)(-1300 3375);
WIRE 16 -1 (-2725 3375)(-1450 3375);
WIRE 16 -1 (-2725 3825)(-2725 3375);
WIRE 16 -1 (-3375 3375)(-2725 3375);
FORCEPROP 2 LAST SIG_NAME VR_VRRDY_PVCCIN_CPU1
J 0
(-3275 3390);
DISPLAY 0.617021 (-3275 3390);
PAINT ORANGE (-3275 3390);
FORCEPROP 2 LASTPROP $XRERR UNIQUE?
J 0
(-3515 3390);
DISPLAY 0.638298 (-3515 3390);
PAINT MONO (-3515 3390);
DISPLAY INVISIBLE (-3515 3390);
WIRE 16 -1 (-1100 3375)(-600 3375);
FORCEPROP 2 LAST SIG_NAME PWRGD_PVCCIN_CPU1
J 0
(-1090 3390);
DISPLAY 0.617021 (-1090 3390);
PAINT ORANGE (-1090 3390);
WIRE 16 -1 (-7450 2775)(-4275 2775);
FORCEPROP 2 LAST SIG_NAME ISENSE_PVCCIN_CPU1_PH4_IMON
J 0
(-7440 2790);
DISPLAY 0.617021 (-7440 2790);
PAINT ORANGE (-7440 2790);
DOT 1 (-6675 1525);
DOT 1 (-6150 1575);
DOT 1 (-6550 2250);
DOT 1 (-6550 2575);
DOT 1 (-6950 3225);
DOT 1 (-6950 3750);
DOT 1 (-6550 3175);
DOT 1 (-6150 3125);
DOT 1 (-6550 3750);
DOT 1 (-6150 3750);
DOT 1 (-5925 1875);
DOT 1 (-5650 1925);
DOT 1 (-5650 2275);
DOT 1 (-5275 3025);
DOT 1 (-5725 3075);
DOT 1 (-5725 3750);
DOT 1 (-5650 3900);
DOT 1 (-4650 2275);
DOT 1 (-4350 4075);
DOT 1 (-6425 4425);
DOT 1 (-6150 4425);
DOT 1 (-5225 4700);
DOT 1 (-3075 3025);
DOT 1 (-4050 4075);
DOT 1 (-2875 2725);
DOT 1 (-2725 3375);
DOT 1 (-2050 3275);
DOT 1 (-1575 1175);
DOT 1 (-1375 2775);
DOT 1 (-1450 3375);
DOT 1 (-3075 4375);
DOT 1 (-2875 4375);
DOT 1 (-2725 4375);
DOT 1 (-2375 4375);
DOT 1 (-2225 4375);
FORCENOTE
ROOM=PROC_VRD_VCCIN_CPU1
(-7805 333) 0;
DISPLAY LEFT (-7805 333);
DISPLAY 2.510638 (-7805 333);
PAINT PURPLE (-7805 333);
QUIT
